G04 ================== begin FILE IDENTIFICATION RECORD ==================*
G04 Layout Name:  D:/<user>/Wistron_project/16342-2/gbr/16342-2.brd*
G04 Film Name:    L4VCC*
G04 File Format:  Gerber RS274X*
G04 File Origin:  Cadence Allegro 16.5-S056*
G04 Origin Date:  Mon Aug 07 11:24:44 2017*
G04 *
G04 Layer:  VIA CLASS/L4VCC*
G04 Layer:  PIN/L4VCC*
G04 Layer:  PACKAGE GEOMETRY/PWRVCC*
G04 Layer:  ETCH/L4VCC*
G04 Layer:  DRAWING FORMAT/LAYER_PCB_STORY*
G04 Layer:  DRAWING FORMAT/LAYER_L4VCC*
G04 *
G04 Offset:    (0.00 0.00)*
G04 Mirror:    No*
G04 Mode:      Negative*
G04 Rotation:  0*
G04 FullContactRelief:  No*
G04 UndefLineWidth:     6.00*
G04 ================== end FILE IDENTIFICATION RECORD ====================*
%FSLAX35Y35*MOIN*%
%IR0*IPPOS*OFA0.00000B0.00000*MIA0B0*SFA1.00000B1.00000*%
%ADD27O,.072X.123*%
%ADD12C,.03*%
%ADD16C,.032*%
%ADD24C,.06*%
%ADD34C,.034*%
%ADD31C,.043*%
%ADD30C,.062*%
%ADD39C,.063*%
%ADD36C,.072*%
%ADD20C,.036*%
%ADD38C,.091*%
%ADD23C,.028*%
%ADD26C,.056*%
%ADD29C,.076*%
%ADD10C,.068*%
%AMMACRO40*
4,1,15,.00398,.00044,
.003999,.000208,
.004004,-.000025,
.003996,-.000258,
.00398,-.00044,
.00483,-.00129,
.004897,-.001007,
.004947,-.000721,
.004981,-.000432,
.004997,-.000141,
.004997,.000149,
.00498,.00044,
.004946,.000729,
.004895,.001015,
.00483,.00129,
.00398,.00044,
45.*
4,1,15,.00044,-.00398,
.000208,-.003999,
-.000025,-.004004,
-.000258,-.003996,
-.00044,-.00398,
-.00129,-.00483,
-.001007,-.004897,
-.000721,-.004947,
-.000432,-.004981,
-.000141,-.004997,
.000149,-.004997,
.00044,-.00498,
.000729,-.004946,
.001015,-.004895,
.00129,-.00483,
.00044,-.00398,
45.*
4,1,15,-.00398,-.00044,
-.003999,-.000208,
-.004004,.000025,
-.003996,.000258,
-.00398,.00044,
-.00483,.00129,
-.004897,.001007,
-.004947,.000721,
-.004981,.000432,
-.004997,.000141,
-.004997,-.000149,
-.00498,-.00044,
-.004946,-.000729,
-.004895,-.001015,
-.00483,-.00129,
-.00398,-.00044,
45.*
4,1,15,-.00044,.00398,
-.000208,.003999,
.000025,.004004,
.000258,.003996,
.00044,.00398,
.00129,.00483,
.001007,.004897,
.000721,.004947,
.000432,.004981,
.000141,.004997,
-.000149,.004997,
-.00044,.00498,
-.000729,.004946,
-.001015,.004895,
-.00129,.00483,
-.00044,.00398,
45.*
%
%ADD40MACRO40*%
%AMMACRO22*
4,1,15,.00398,.00044,
.003999,.000208,
.004004,-.000025,
.003996,-.000258,
.00398,-.00044,
.00483,-.00129,
.004897,-.001007,
.004947,-.000721,
.004981,-.000432,
.004997,-.000141,
.004997,.000149,
.00498,.00044,
.004946,.000729,
.004895,.001015,
.00483,.00129,
.00398,.00044,
90.*
4,1,15,.00044,-.00398,
.000208,-.003999,
-.000025,-.004004,
-.000258,-.003996,
-.00044,-.00398,
-.00129,-.00483,
-.001007,-.004897,
-.000721,-.004947,
-.000432,-.004981,
-.000141,-.004997,
.000149,-.004997,
.00044,-.00498,
.000729,-.004946,
.001015,-.004895,
.00129,-.00483,
.00044,-.00398,
90.*
4,1,15,-.00398,-.00044,
-.003999,-.000208,
-.004004,.000025,
-.003996,.000258,
-.00398,.00044,
-.00483,.00129,
-.004897,.001007,
-.004947,.000721,
-.004981,.000432,
-.004997,.000141,
-.004997,-.000149,
-.00498,-.00044,
-.004946,-.000729,
-.004895,-.001015,
-.00483,-.00129,
-.00398,-.00044,
90.*
4,1,15,-.00044,.00398,
-.000208,.003999,
.000025,.004004,
.000258,.003996,
.00044,.00398,
.00129,.00483,
.001007,.004897,
.000721,.004947,
.000432,.004981,
.000141,.004997,
-.000149,.004997,
-.00044,.00498,
-.000729,.004946,
-.001015,.004895,
-.00129,.00483,
-.00044,.00398,
90.*
%
%ADD22MACRO22*%
%AMMACRO11*
4,1,15,.00398,.00044,
.003999,.000208,
.004004,-.000025,
.003996,-.000258,
.00398,-.00044,
.00483,-.00129,
.004897,-.001007,
.004947,-.000721,
.004981,-.000432,
.004997,-.000141,
.004997,.000149,
.00498,.00044,
.004946,.000729,
.004895,.001015,
.00483,.00129,
.00398,.00044,
0.0*
4,1,15,.00044,-.00398,
.000208,-.003999,
-.000025,-.004004,
-.000258,-.003996,
-.00044,-.00398,
-.00129,-.00483,
-.001007,-.004897,
-.000721,-.004947,
-.000432,-.004981,
-.000141,-.004997,
.000149,-.004997,
.00044,-.00498,
.000729,-.004946,
.001015,-.004895,
.00129,-.00483,
.00044,-.00398,
0.0*
4,1,15,-.00398,-.00044,
-.003999,-.000208,
-.004004,.000025,
-.003996,.000258,
-.00398,.00044,
-.00483,.00129,
-.004897,.001007,
-.004947,.000721,
-.004981,.000432,
-.004997,.000141,
-.004997,-.000149,
-.00498,-.00044,
-.004946,-.000729,
-.004895,-.001015,
-.00483,-.00129,
-.00398,-.00044,
0.0*
4,1,15,-.00044,.00398,
-.000208,.003999,
.000025,.004004,
.000258,.003996,
.00044,.00398,
.00129,.00483,
.001007,.004897,
.000721,.004947,
.000432,.004981,
.000141,.004997,
-.000149,.004997,
-.00044,.00498,
-.000729,.004946,
-.001015,.004895,
-.00129,.00483,
-.00044,.00398,
0.0*
%
%ADD11MACRO11*%
%ADD35O,.154X.217*%
%ADD33C,.122*%
%ADD13C,.114*%
%ADD32C,.125*%
%ADD25C,.208*%
%ADD18O,.296X.162*%
%ADD28O,.072X.096*%
%ADD19C,.158*%
%ADD14C,.178*%
%ADD17C,.198*%
%AMMACRO37*
4,1,15,.00398,.00044,
.003999,.000208,
.004004,-.000025,
.003996,-.000258,
.00398,-.00044,
.00483,-.00129,
.004897,-.001007,
.004947,-.000721,
.004981,-.000432,
.004997,-.000141,
.004997,.000149,
.00498,.00044,
.004946,.000729,
.004895,.001015,
.00483,.00129,
.00398,.00044,
225.*
4,1,15,.00044,-.00398,
.000208,-.003999,
-.000025,-.004004,
-.000258,-.003996,
-.00044,-.00398,
-.00129,-.00483,
-.001007,-.004897,
-.000721,-.004947,
-.000432,-.004981,
-.000141,-.004997,
.000149,-.004997,
.00044,-.00498,
.000729,-.004946,
.001015,-.004895,
.00129,-.00483,
.00044,-.00398,
225.*
4,1,15,-.00398,-.00044,
-.003999,-.000208,
-.004004,.000025,
-.003996,.000258,
-.00398,.00044,
-.00483,.00129,
-.004897,.001007,
-.004947,.000721,
-.004981,.000432,
-.004997,.000141,
-.004997,-.000149,
-.00498,-.00044,
-.004946,-.000729,
-.004895,-.001015,
-.00483,-.00129,
-.00398,-.00044,
225.*
4,1,15,-.00044,.00398,
-.000208,.003999,
.000025,.004004,
.000258,.003996,
.00044,.00398,
.00129,.00483,
.001007,.004897,
.000721,.004947,
.000432,.004981,
.000141,.004997,
-.000149,.004997,
-.00044,.00498,
-.000729,.004946,
-.001015,.004895,
-.00129,.00483,
-.00044,.00398,
225.*
%
%ADD37MACRO37*%
%AMMACRO21*
4,1,15,.00398,.00044,
.003999,.000208,
.004004,-.000025,
.003996,-.000258,
.00398,-.00044,
.00483,-.00129,
.004897,-.001007,
.004947,-.000721,
.004981,-.000432,
.004997,-.000141,
.004997,.000149,
.00498,.00044,
.004946,.000729,
.004895,.001015,
.00483,.00129,
.00398,.00044,
180.*
4,1,15,.00044,-.00398,
.000208,-.003999,
-.000025,-.004004,
-.000258,-.003996,
-.00044,-.00398,
-.00129,-.00483,
-.001007,-.004897,
-.000721,-.004947,
-.000432,-.004981,
-.000141,-.004997,
.000149,-.004997,
.00044,-.00498,
.000729,-.004946,
.001015,-.004895,
.00129,-.00483,
.00044,-.00398,
180.*
4,1,15,-.00398,-.00044,
-.003999,-.000208,
-.004004,.000025,
-.003996,.000258,
-.00398,.00044,
-.00483,.00129,
-.004897,.001007,
-.004947,.000721,
-.004981,.000432,
-.004997,.000141,
-.004997,-.000149,
-.00498,-.00044,
-.004946,-.000729,
-.004895,-.001015,
-.00483,-.00129,
-.00398,-.00044,
180.*
4,1,15,-.00044,.00398,
-.000208,.003999,
.000025,.004004,
.000258,.003996,
.00044,.00398,
.00129,.00483,
.001007,.004897,
.000721,.004947,
.000432,.004981,
.000141,.004997,
-.000149,.004997,
-.00044,.00498,
-.000729,.004946,
-.001015,.004895,
-.00129,.00483,
-.00044,.00398,
180.*
%
%ADD21MACRO21*%
%AMMACRO15*
4,1,15,.00398,.00044,
.003999,.000208,
.004004,-.000025,
.003996,-.000258,
.00398,-.00044,
.00483,-.00129,
.004897,-.001007,
.004947,-.000721,
.004981,-.000432,
.004997,-.000141,
.004997,.000149,
.00498,.00044,
.004946,.000729,
.004895,.001015,
.00483,.00129,
.00398,.00044,
270.*
4,1,15,.00044,-.00398,
.000208,-.003999,
-.000025,-.004004,
-.000258,-.003996,
-.00044,-.00398,
-.00129,-.00483,
-.001007,-.004897,
-.000721,-.004947,
-.000432,-.004981,
-.000141,-.004997,
.000149,-.004997,
.00044,-.00498,
.000729,-.004946,
.001015,-.004895,
.00129,-.00483,
.00044,-.00398,
270.*
4,1,15,-.00398,-.00044,
-.003999,-.000208,
-.004004,.000025,
-.003996,.000258,
-.00398,.00044,
-.00483,.00129,
-.004897,.001007,
-.004947,.000721,
-.004981,.000432,
-.004997,.000141,
-.004997,-.000149,
-.00498,-.00044,
-.004946,-.000729,
-.004895,-.001015,
-.00483,-.00129,
-.00398,-.00044,
270.*
4,1,15,-.00044,.00398,
-.000208,.003999,
.000025,.004004,
.000258,.003996,
.00044,.00398,
.00129,.00483,
.001007,.004897,
.000721,.004947,
.000432,.004981,
.000141,.004997,
-.000149,.004997,
-.00044,.00498,
-.000729,.004946,
-.001015,.004895,
-.00129,.00483,
-.00044,.00398,
270.*
%
%ADD15MACRO15*%
%ADD41C,.02*%
%ADD42C,.006*%
%ADD51C,.07204*%
%ADD49C,.05604*%
%ADD52C,.05804*%
%ADD56C,.06804*%
%ADD57C,.08704*%
%ADD53C,.08382*%
%ADD43C,.08982*%
%ADD55O,.15002X.21302*%
%ADD54O,.15004X.21304*%
%ADD46C,.11004*%
%ADD58C,.12104*%
%ADD59C,.11804*%
%ADD47C,.15404*%
%ADD50O,.29202X.15802*%
%ADD44O,.29204X.15804*%
%ADD45C,.37406*%
%ADD48C,.29604*%
G75*
%LPD*%
G75*
G36*
G01X-6000Y-6000D02*
X931197D01*
Y769780D01*
X-6000D01*
Y-6000D01*
G37*
%LPC*%
G75*
G36*
G01X43603Y757998D02*
G03X52686Y721780I5609J-17841D01*
G02X53043Y721104I74J-393D01*
G01X38656Y706717D01*
G02X38029Y706796I-283J283D01*
G03X30491Y699258I-4732J-2806D01*
G02X30570Y698631I-204J-344D01*
G01X9650Y677711D01*
Y466913D01*
G03X9870Y466383I750J1D01*
G01X47183Y429070D01*
G03X47713Y428850I531J530D01*
G01X115197D01*
Y5000D01*
X5000D01*
Y723229D01*
X22776Y758780D01*
X43484D01*
G02X43603Y757998I-1J-400D01*
G37*
G36*
G01X126115Y608827D02*
X124483Y607196D01*
X114445D01*
X114413Y607208D01*
G03X112931I-741J-2074D01*
G01X112899Y607196D01*
X103946D01*
X103912Y607209D01*
G03X102336I-788J-2056D01*
G01X102302Y607196D01*
X101651D01*
X100203Y608644D01*
Y619409D01*
X84723Y634889D01*
X48095D01*
X46250Y636734D01*
Y668189D01*
X61067Y683006D01*
G02X61750Y682723I283J-283D01*
G01Y676689D01*
X65189Y673250D01*
X75327D01*
G03X77771I1222J2297D01*
G01X80327D01*
G03X82771I1222J2297D01*
G01X90311D01*
X97943Y680882D01*
X122943D01*
X148081Y706020D01*
X153174D01*
X157593Y710439D01*
Y715532D01*
X182811Y740750D01*
X292689D01*
X295250Y738189D01*
Y733189D01*
X297189Y731250D01*
X314189D01*
X317750Y727689D01*
Y712127D01*
X317748Y712112D01*
G03Y711328I2572J-392D01*
G01X317750Y711313D01*
Y706689D01*
X325393Y699046D01*
X325290Y698908D01*
G03X328504Y695935I1772J-1308D01*
G01X330750Y693689D01*
Y692775D01*
X330737Y692741D01*
G03Y691199I2063J-771D01*
G01X330750Y691165D01*
Y685011D01*
X330739Y684979D01*
G03Y683561I2085J-709D01*
G01X330750Y683529D01*
Y677311D01*
X318689Y665250D01*
X307189D01*
X305689Y663750D01*
X299689D01*
X297750Y661811D01*
Y649689D01*
X301189Y646250D01*
X333889D01*
X338489Y641650D01*
X383099D01*
G02X383498Y641258I-1J-400D01*
G03X386163Y639147I2202J42D01*
G01X386269Y639170D01*
X386750Y638689D01*
Y579180D01*
X381250Y573680D01*
Y566315D01*
G03X381223Y564054I1876J-1153D01*
G01X381250Y564008D01*
Y563168D01*
G03Y560302I1672J-1433D01*
G01Y557489D01*
X389050Y549689D01*
Y536311D01*
X383750Y531011D01*
Y186811D01*
X382689Y185750D01*
X376988D01*
X368250Y194488D01*
Y203311D01*
X365811Y205750D01*
X334111D01*
X332150Y207711D01*
Y382716D01*
X344825Y395391D01*
Y424236D01*
X315962Y453099D01*
G02X316218Y453781I283J283D01*
G03X298961Y462757I-1257J18660D01*
G02X298619Y462150I-342J-207D01*
G01X214393D01*
G03X211925I-1234J-1824D01*
G01X87208D01*
G02X86866Y462757I0J400D01*
G03X54189Y463975I-16000J9684D01*
G02X53550Y463511I-357J-181D01*
G01X46250Y470811D01*
Y516768D01*
X46877Y517395D01*
X99306D01*
X102017Y520106D01*
Y525337D01*
X108709Y532029D01*
X138970D01*
X159579Y552638D01*
X169206D01*
G03X169736Y552858I-1J750D01*
G01X170855Y553977D01*
G03X171075Y554507I-530J531D01*
G01Y555514D01*
X175750Y560189D01*
Y567689D01*
X177750Y569689D01*
Y580311D01*
X175530Y582530D01*
G03X175000Y582750I-531J-530D01*
G01X168682D01*
X168054Y583378D01*
Y587363D01*
X166071Y589346D01*
X161937D01*
X161540Y589743D01*
Y590707D01*
X160030Y592217D01*
X158573D01*
X155861Y594929D01*
Y597500D01*
X144533Y608827D01*
G03X144003Y609047I-531J-530D01*
G01X142248D01*
G03X138842Y609406I-1848J-1197D01*
G02X138558I-142J141D01*
G03X135152Y609047I-1558J-1556D01*
G01X132548D01*
G03X128852I-1848J-1197D01*
G01X126645D01*
G03X126115Y608827I1J-750D01*
G37*
G36*
G01X585367Y36250D02*
X599454Y50337D01*
X611433D01*
X619020Y42750D01*
X676387D01*
X679150Y45513D01*
Y58748D01*
X683467Y63065D01*
X801167D01*
X832542Y94440D01*
Y360691D01*
X832558Y360728D01*
G03Y362450I-2027J861D01*
G01X832542Y362487D01*
Y379343D01*
X841552Y388353D01*
X877606D01*
X882146Y383813D01*
X909990D01*
X913850Y379953D01*
Y118511D01*
X827404Y32065D01*
X708884D01*
X688569Y11750D01*
X294311D01*
X292811Y13250D01*
X292520D01*
Y429331D01*
G03X283583Y438268I-8937J0D01*
G01X124134D01*
G03X115277Y430523I0J-8937D01*
G01X115253Y430350D01*
X48024D01*
X11150Y467224D01*
Y677089D01*
X32594Y698533D01*
X32689Y698522D01*
G03X38765Y704598I608J5468D01*
G01X38754Y704693D01*
X57406Y723345D01*
X57436Y723360D01*
G03X64405Y729250I-8223J16798D01*
G01X95189D01*
X97250Y727189D01*
Y701311D01*
X90812Y694873D01*
X70812D01*
X44750Y668811D01*
Y636458D01*
G03Y636389I751J-35D01*
G01Y631737D01*
G03Y631668I751J-35D01*
G01Y523762D01*
G03Y523693I751J-35D01*
G01Y470189D01*
X62689Y452250D01*
X78659D01*
G03X78662I1J750D01*
G03X79259Y452498I-3J850D01*
G01X87411Y460650D01*
X131832D01*
G03X133722I945J1989D01*
G01X298189D01*
X306341Y452499D01*
G03X306343Y452497I531J529D01*
G03X306940Y452250I599J603D01*
G01X314689D01*
X343325Y423614D01*
Y396013D01*
X330650Y383338D01*
Y207089D01*
X333489Y204250D01*
X365189D01*
X366750Y202689D01*
Y193866D01*
X376366Y184250D01*
X382689D01*
X383750Y183189D01*
Y82022D01*
X384268Y81504D01*
X384170Y81366D01*
G03X387241Y78295I1794J-1277D01*
G01X387379Y78393D01*
X400457Y65315D01*
X409124D01*
X434689Y39750D01*
X482131D01*
X482157Y39743D01*
G03X483297I570J2127D01*
G01X483323Y39750D01*
X486288D01*
X486298Y39749D01*
G03X486756I229J2190D01*
G01X486766Y39750D01*
X504811D01*
X507811Y42750D01*
X524138D01*
G03X526669Y41177I2392J1025D01*
G01X526758Y41181D01*
X531689Y36250D01*
X585367D01*
G37*
G36*
G01X134813Y607547D02*
X134847Y607389D01*
G03X138558Y606294I2153J461D01*
G02X138842I142J-141D01*
G03X142553Y607389I1558J1556D01*
G01X142587Y607547D01*
X143692D01*
X154361Y596878D01*
Y594307D01*
X157951Y590717D01*
X159408D01*
X160040Y590085D01*
Y589121D01*
X161315Y587846D01*
X165449D01*
X166554Y586741D01*
Y583067D01*
G03X166774Y582537I750J1D01*
G01X167841Y581470D01*
G03X168371Y581250I531J530D01*
G01X174689D01*
X176250Y579689D01*
Y570311D01*
X174250Y568311D01*
Y560811D01*
X169795Y556355D01*
G03X169575Y555825I530J-531D01*
G01Y554818D01*
X168895Y554138D01*
X158957D01*
X138348Y533529D01*
X108087D01*
X100517Y525959D01*
Y520728D01*
X98684Y518895D01*
X47349D01*
X46250Y519994D01*
Y523660D01*
X46251Y523667D01*
G03Y523788I-750J60D01*
G01X46250Y523795D01*
Y606134D01*
X46251Y606135D01*
Y606757D01*
X46250Y606758D01*
Y631392D01*
X48247Y633389D01*
X84101D01*
X98703Y618787D01*
Y608022D01*
X101029Y605696D01*
X125105D01*
X125324Y605915D01*
Y605916D01*
X126956Y607547D01*
X128513D01*
X128547Y607389D01*
G03X132853I2153J461D01*
G01X132887Y607547D01*
X133092D01*
X133123Y607536D01*
G03X134547I712J2084D01*
G01X134578Y607547D01*
X134813D01*
G37*
G36*
G01X411750Y100689D02*
X455189Y57250D01*
X458120D01*
X458156Y57096D01*
G03X462444I2144J504D01*
G01X462480Y57250D01*
X493311D01*
X495811Y59750D01*
X520689D01*
X525689Y54750D01*
X552811D01*
X567850Y69789D01*
Y87945D01*
X569606Y89701D01*
X605966D01*
X624315Y71352D01*
X624330Y71324D01*
G03X625464Y70190I2317J1183D01*
G01X625492Y70175D01*
X626614Y69053D01*
X667038D01*
X677650Y58441D01*
Y46135D01*
X675765Y44250D01*
X620418D01*
X620198Y44470D01*
X619422D01*
X612055Y51837D01*
X598832D01*
X584745Y37750D01*
X532311D01*
X525811Y44250D01*
X507189D01*
X504189Y41250D01*
X469496D01*
G03X466504I-1496J-1750D01*
G01X435311D01*
X409746Y66815D01*
X401079D01*
X388142Y79752D01*
X388153Y79847D01*
G03X385722Y82278I-2189J242D01*
G01X385627Y82267D01*
X385250Y82644D01*
Y530389D01*
X390550Y535689D01*
Y550311D01*
X385109Y555752D01*
G03X383935Y556926I-2029J-855D01*
G01X382750Y558111D01*
Y573058D01*
X388250Y578558D01*
Y579660D01*
X388265Y579697D01*
G03Y581351I-2041J827D01*
G01X388250Y581388D01*
Y639311D01*
X387516Y640045D01*
X387595Y640179D01*
G03X384506Y643150I-1895J1121D01*
G01X374844D01*
X374819Y643157D01*
G03X373685I-567J-2128D01*
G01X373660Y643150D01*
X339111D01*
X334511Y647750D01*
X301811D01*
X299250Y650311D01*
Y661189D01*
X300311Y662250D01*
X306311D01*
X307811Y663750D01*
X319311D01*
X332250Y676689D01*
Y694311D01*
X329247Y697314D01*
X329255Y697407D01*
G03X326869Y699793I-2193J193D01*
G01X326776Y699785D01*
X319250Y707311D01*
Y728311D01*
X314811Y732750D01*
X297811D01*
X296750Y733811D01*
Y738811D01*
X293311Y742250D01*
X182189D01*
X156093Y716154D01*
Y711061D01*
X152552Y707520D01*
X147459D01*
X133451Y693512D01*
X133406Y693498D01*
G03X131752Y691844I817J-2471D01*
G01X131738Y691799D01*
X122321Y682382D01*
X97321D01*
X89689Y674750D01*
X65811D01*
X63250Y677311D01*
Y685189D01*
X71434Y693373D01*
X91123D01*
G03X91653Y693593I-1J750D01*
G01X98750Y700689D01*
Y727811D01*
X96250Y730311D01*
Y741289D01*
X97534Y742573D01*
X97666Y742500D01*
G03X101203Y746037I1262J2275D01*
G01X101130Y746169D01*
X108911Y753950D01*
X109148D01*
X109207Y753858D01*
G03X113640Y753950I2188J1408D01*
G01X114150D01*
G03X118640I2245J1316D01*
G01X119150D01*
G03X123640I2245J1316D01*
G01X124150D01*
G03X128640I2245J1316D01*
G01X129150D01*
G03X133640I2245J1316D01*
G01X134150D01*
G03X138640I2245J1316D01*
G01X139150D01*
G03X143640I2245J1316D01*
G01X144150D01*
G03X148640I2245J1316D01*
G01X149150D01*
G03X153640I2245J1316D01*
G01X154150D01*
G03X158640I2245J1316D01*
G01X159150D01*
G03X163640I2245J1316D01*
G01X164150D01*
G03X168640I2245J1316D01*
G01X169150D01*
G03X173640I2245J1316D01*
G01X174150D01*
G03X178640I2245J1316D01*
G01X179150D01*
G03X183640I2245J1316D01*
G01X184150D01*
G03X188640I2245J1316D01*
G01X189150D01*
G03X193640I2245J1316D01*
G01X194150D01*
G03X198640I2245J1316D01*
G01X199150D01*
G03X203640I2245J1316D01*
G01X204150D01*
G03X208640I2245J1316D01*
G01X209150D01*
G03X213640I2245J1316D01*
G01X214150D01*
G03X218640I2245J1316D01*
G01X219150D01*
G03X223640I2245J1316D01*
G01X224150D01*
G03X228640I2245J1316D01*
G01X229150D01*
G03X233640I2245J1316D01*
G01X234150D01*
G03X238640I2245J1316D01*
G01X239150D01*
G03X243640I2245J1316D01*
G01X244150D01*
G03X248640I2245J1316D01*
G01X249150D01*
G03X253640I2245J1316D01*
G01X254150D01*
G03X258640I2245J1316D01*
G01X259150D01*
G03X263640I2245J1316D01*
G01X264150D01*
G03X268640I2245J1316D01*
G01X269150D01*
G03X273640I2245J1316D01*
G01X274150D01*
G03X278640I2245J1316D01*
G01X279150D01*
G03X283640I2245J1316D01*
G01X284150D01*
G03X288640I2245J1316D01*
G01X289150D01*
G03X293640I2245J1316D01*
G01X294150D01*
G03X298640I2245J1316D01*
G01X299150D01*
G03X303640I2245J1316D01*
G01X304150D01*
G03X308640I2245J1316D01*
G01X309150D01*
G03X313640I2245J1316D01*
G01X314150D01*
G03X318640I2245J1316D01*
G01X319150D01*
G03X323640I2245J1316D01*
G01X324150D01*
G03X325626Y752780I2245J1316D01*
G01X325673Y752766D01*
X348525Y729914D01*
G03X353913Y724520I15648J10243D01*
G01X353930Y724509D01*
X388297Y690142D01*
X388312Y690104D01*
G03X389533Y688883I2043J822D01*
G01X389571Y688868D01*
X403268Y675171D01*
Y188976D01*
G03X411290Y182088I6968J0D01*
G02X411750Y181692I60J-396D01*
G01Y100689D01*
G37*
G36*
G01X138562Y756706D02*
G03X134228I-2167J-1440D01*
G02X133562I-333J222D01*
G03X129228I-2167J-1440D01*
G02X128562I-333J222D01*
G03X124228I-2167J-1440D01*
G02X123562I-333J222D01*
G03X119228I-2167J-1440D01*
G02X118562I-333J222D01*
G03X114228I-2167J-1440D01*
G02X113562I-333J222D01*
G03X108818Y755623I-2167J-1440D01*
G01X108794Y755450D01*
X108289D01*
X99992Y747153D01*
X99870Y747200D01*
G03X96503Y743833I-942J-2425D01*
G01X96550Y743711D01*
X94750Y741911D01*
Y730750D01*
X66058D01*
G02X65705Y731339I0J400D01*
G03X54821Y757998I-16493J8818D01*
G02X54941Y758780I120J382D01*
G01X358444D01*
G02X358564Y757998I0J-400D01*
G03X346041Y735571I5609J-17842D01*
G02X345371Y735190I-388J-98D01*
G01X325111Y755450D01*
X323996D01*
X323972Y755623D01*
G03X319228Y756706I-2577J-357D01*
G02X318562I-333J222D01*
G03X314228I-2167J-1440D01*
G02X313562I-333J222D01*
G03X309228I-2167J-1440D01*
G02X308562I-333J222D01*
G03X304228I-2167J-1440D01*
G02X303562I-333J222D01*
G03X299228I-2167J-1440D01*
G02X298562I-333J222D01*
G03X294228I-2167J-1440D01*
G02X293562I-333J222D01*
G03X289228I-2167J-1440D01*
G02X288562I-333J222D01*
G03X284228I-2167J-1440D01*
G02X283562I-333J222D01*
G03X279228I-2167J-1440D01*
G02X278562I-333J222D01*
G03X274228I-2167J-1440D01*
G02X273562I-333J222D01*
G03X269228I-2167J-1440D01*
G02X268562I-333J222D01*
G03X264228I-2167J-1440D01*
G02X263562I-333J222D01*
G03X259228I-2167J-1440D01*
G02X258562I-333J222D01*
G03X254228I-2167J-1440D01*
G02X253562I-333J222D01*
G03X249228I-2167J-1440D01*
G02X248562I-333J222D01*
G03X244228I-2167J-1440D01*
G02X243562I-333J222D01*
G03X239228I-2167J-1440D01*
G02X238562I-333J222D01*
G03X234228I-2167J-1440D01*
G02X233562I-333J222D01*
G03X229228I-2167J-1440D01*
G02X228562I-333J222D01*
G03X224228I-2167J-1440D01*
G02X223562I-333J222D01*
G03X219228I-2167J-1440D01*
G02X218562I-333J222D01*
G03X214228I-2167J-1440D01*
G02X213562I-333J222D01*
G03X209228I-2167J-1440D01*
G02X208562I-333J222D01*
G03X204228I-2167J-1440D01*
G02X203562I-333J222D01*
G03X199228I-2167J-1440D01*
G02X198562I-333J222D01*
G03X194228I-2167J-1440D01*
G02X193562I-333J222D01*
G03X189228I-2167J-1440D01*
G02X188562I-333J222D01*
G03X184228I-2167J-1440D01*
G02X183562I-333J222D01*
G03X179228I-2167J-1440D01*
G02X178562I-333J222D01*
G03X174228I-2167J-1440D01*
G02X173562I-333J222D01*
G03X169228I-2167J-1440D01*
G02X168562I-333J222D01*
G03X164228I-2167J-1440D01*
G02X163562I-333J222D01*
G03X159228I-2167J-1440D01*
G02X158562I-333J222D01*
G03X154228I-2167J-1440D01*
G02X153562I-333J222D01*
G03X149228I-2167J-1440D01*
G02X148562I-333J222D01*
G03X144228I-2167J-1440D01*
G02X143562I-333J222D01*
G03X139228I-2167J-1440D01*
G02X138562I-333J222D01*
G37*
G36*
G01X606592Y624139D02*
G03X617818I5613J-17840D01*
G02X617936Y624921I119J382D01*
G01X842520D01*
G03X851457Y633858I0J8937D01*
G01Y758780D01*
X870256D01*
G02X870375Y757998I-1J-400D01*
G03X881593I5609J-17841D01*
G02X881712Y758780I120J382D01*
G01X902421D01*
X920197Y723229D01*
Y5000D01*
X292520D01*
Y8650D01*
X292711D01*
X294311Y10250D01*
X689191D01*
X709506Y30565D01*
X828026D01*
X915350Y117889D01*
Y380575D01*
X910612Y385313D01*
X882768D01*
X878228Y389853D01*
X840930D01*
X831042Y379965D01*
Y95062D01*
X800545Y64565D01*
X682845D01*
X678246Y59966D01*
X667660Y70553D01*
X627236D01*
X606588Y91201D01*
X569606D01*
X567850Y92957D01*
Y115976D01*
X567853Y115979D01*
Y116601D01*
X567850Y116604D01*
Y182221D01*
G03X573110Y188975I-1708J6756D01*
G01Y294405D01*
G02X573809Y294670I400J0D01*
G03Y319504I13986J12417D01*
G02X573110Y319769I-299J265D01*
G01Y463810D01*
G02X573867Y463990I400J-1D01*
G03Y480892I16684J8451D01*
G02X573110Y481072I-357J181D01*
G01Y589370D01*
X590885Y624921D01*
X606474D01*
G02X606592Y624139I-1J-400D01*
G37*
G36*
G01X455811Y58750D02*
X413250Y101311D01*
Y182693D01*
G03X415090Y183976I-3014J6283D01*
G01X476838D01*
Y71644D01*
G03Y68976I1752J-1334D01*
G01Y63975D01*
G03Y61625I1862J-1175D01*
G01Y59578D01*
X476010Y58750D01*
X462178D01*
G03X458422I-1878J-1150D01*
G01X455811D01*
G37*
G36*
G01X385492Y758780D02*
X403268Y723229D01*
Y677776D01*
G02X402927Y677634I-200J0D01*
G01X402817Y677744D01*
X402807Y677758D01*
G03X402258Y678307I-1807J-1258D01*
G01X402244Y678317D01*
X359206Y721355D01*
G02X359587Y722025I283J282D01*
G03X369782Y757998I4585J18132D01*
G02X369902Y758780I120J382D01*
G01X385492D01*
G37*
G36*
G01X526311Y56250D02*
X521311Y61250D01*
X520483D01*
G03X517297I-1593J-1520D01*
G01X495189D01*
X492689Y58750D01*
X479232D01*
X478338Y59644D01*
Y183976D01*
X530973D01*
Y120048D01*
X534353Y116668D01*
X565664D01*
X566350Y115982D01*
Y70411D01*
X552189Y56250D01*
X526311D01*
G37*
G36*
G01X534975Y118168D02*
X532473Y120670D01*
Y183976D01*
X561288D01*
G03X566150Y182008I4853J5000D01*
G02X566350Y181808I0J-200D01*
G01Y118973D01*
X565545Y118168D01*
X534975D01*
G37*
%LPD*%
G75*
G36*
G01X336084Y362935D02*
Y359510D01*
G02X333080I-1502J-36D01*
G01Y362938D01*
G02X336084I1502J36D01*
G01Y362935D01*
G37*
G36*
G01Y337682D02*
Y334257D01*
G02X333080I-1502J-36D01*
G01Y337685D01*
G02X336084I1502J36D01*
G01Y337682D01*
G37*
G36*
G01X336094Y312545D02*
Y309123D01*
X336095Y309120D01*
G02X333091I-1502J-36D01*
G01X333092Y309123D01*
Y312545D01*
X333091Y312548D01*
G02X336095I1502J36D01*
G01X336094Y312545D01*
G37*
G36*
G01X335608Y287315D02*
Y283893D01*
X335609Y283890D01*
G02X332605I-1502J-36D01*
G01X332606Y283893D01*
Y287315D01*
X332605Y287318D01*
G02X335609I1502J36D01*
G01X335608Y287315D01*
G37*
G36*
G01X329684Y375479D02*
Y372054D01*
G02X326680I-1502J-36D01*
G01Y375482D01*
G02X329684I1502J36D01*
G01Y375479D01*
G37*
G36*
G01X305768Y369253D02*
Y365831D01*
X305769Y365828D01*
G02X302765I-1502J-36D01*
G01X302766Y365831D01*
Y369253D01*
X302765Y369256D01*
G02X305769I1502J36D01*
G01X305768Y369253D01*
G37*
G36*
G01X309068Y356653D02*
Y353231D01*
X309069Y353228D01*
G02X306065I-1502J-36D01*
G01X306066Y353231D01*
Y356653D01*
X306065Y356656D01*
G02X309069I1502J36D01*
G01X309068Y356653D01*
G37*
G36*
G01X329688Y350277D02*
Y346855D01*
X329689Y346852D01*
G02X326685I-1502J-36D01*
G01X326686Y346855D01*
Y350277D01*
X326685Y350280D01*
G02X329689I1502J36D01*
G01X329688Y350277D01*
G37*
G36*
G01X305768Y344053D02*
Y340631D01*
X305769Y340628D01*
G02X302765I-1502J-36D01*
G01X302766Y340631D01*
Y344053D01*
X302765Y344056D01*
G02X305769I1502J36D01*
G01X305768Y344053D01*
G37*
G36*
G01X309068Y331453D02*
Y328031D01*
X309069Y328028D01*
G02X306065I-1502J-36D01*
G01X306066Y328031D01*
Y331453D01*
X306065Y331456D01*
G02X309069I1502J36D01*
G01X309068Y331453D01*
G37*
G36*
G01X329684Y325085D02*
Y321660D01*
G02X326680I-1502J-36D01*
G01Y325088D01*
G02X329684I1502J36D01*
G01Y325085D01*
G37*
G36*
G01X305768Y318853D02*
Y315431D01*
X305769Y315428D01*
G02X302765I-1502J-36D01*
G01X302766Y315431D01*
Y318853D01*
X302765Y318856D01*
G02X305769I1502J36D01*
G01X305768Y318853D01*
G37*
G36*
G01X309068Y306253D02*
Y302831D01*
X309069Y302828D01*
G02X306065I-1502J-36D01*
G01X306066Y302831D01*
Y306253D01*
X306065Y306256D01*
G02X309069I1502J36D01*
G01X309068Y306253D01*
G37*
G36*
G01X329684Y299938D02*
Y296513D01*
G02X326680I-1502J-36D01*
G01Y299941D01*
G02X329684I1502J36D01*
G01Y299938D01*
G37*
G36*
G01X305768Y293653D02*
Y290231D01*
X305769Y290228D01*
G02X302765I-1502J-36D01*
G01X302766Y290231D01*
Y293653D01*
X302765Y293656D01*
G02X305769I1502J36D01*
G01X305768Y293653D01*
G37*
G36*
G01X309068Y281053D02*
Y277631D01*
X309069Y277628D01*
G02X306065I-1502J-36D01*
G01X306066Y277631D01*
Y281053D01*
X306065Y281056D01*
G02X309069I1502J36D01*
G01X309068Y281053D01*
G37*
G36*
G01X306050Y268469D02*
Y265044D01*
G02X303046I-1502J-36D01*
G01Y268472D01*
G02X306050I1502J36D01*
G01Y268469D01*
G37*
G36*
G01X805747Y555869D02*
X805750Y555872D01*
X808119Y558240D01*
X808122Y558244D01*
G02X810250Y556128I1115J-1007D01*
G01X807872Y553750D01*
G02X805747Y555869I-1109J1013D01*
G37*
G36*
G01X787247D02*
X787250Y555872D01*
X789619Y558240D01*
X789622Y558244D01*
G02X791750Y556128I1115J-1007D01*
G01X789372Y553750D01*
G02X787247Y555869I-1109J1013D01*
G37*
G36*
G01X796747Y555369D02*
X796750Y555372D01*
X799119Y557740D01*
X799122Y557744D01*
G02X801250Y555628I1115J-1007D01*
G01X798872Y553250D01*
G02X796747Y555369I-1109J1013D01*
G37*
G36*
G01X777747Y554869D02*
X777750Y554872D01*
X780119Y557240D01*
X780122Y557244D01*
G02X782250Y555128I1115J-1007D01*
G01X779872Y552750D01*
G02X777747Y554869I-1109J1013D01*
G37*
G36*
G01X824247Y554369D02*
X824250Y554372D01*
X826619Y556740D01*
X826622Y556744D01*
G02X828750Y554628I1115J-1007D01*
G01X826372Y552250D01*
G02X824247Y554369I-1109J1013D01*
G37*
G36*
G01X767247Y553869D02*
X767250Y553872D01*
X769619Y556240D01*
X769622Y556244D01*
G02X771750Y554128I1115J-1007D01*
G01X769372Y551750D01*
G02X767247Y553869I-1109J1013D01*
G37*
G36*
G01X689685Y553463D02*
X687307Y551085D01*
G02X685182Y553204I-1109J1013D01*
G01X685185Y553207D01*
X687554Y555575D01*
X687557Y555579D01*
G02X689685Y553463I1115J-1007D01*
G37*
G36*
G01X707666Y552952D02*
X707669Y552955D01*
X710038Y555323D01*
X710041Y555327D01*
G02X712169Y553211I1115J-1007D01*
G01X709791Y550833D01*
G02X707666Y552952I-1109J1013D01*
G37*
G36*
G01X698437Y552184D02*
X698440Y552187D01*
X700809Y554555D01*
X700812Y554559D01*
G02X702940Y552443I1115J-1007D01*
G01X700562Y550065D01*
G02X698437Y552184I-1109J1013D01*
G37*
G36*
G01X727666Y551052D02*
X727669Y551055D01*
X730038Y553423D01*
X730041Y553427D01*
G02X732169Y551311I1115J-1007D01*
G01X729791Y548933D01*
G02X727666Y551052I-1109J1013D01*
G37*
G36*
G01X716813Y550962D02*
X716816Y550965D01*
X719185Y553333D01*
X719188Y553337D01*
G02X721316Y551221I1115J-1007D01*
G01X718938Y548843D01*
G02X716813Y550962I-1109J1013D01*
G37*
G36*
G01X811747Y549369D02*
X811750Y549372D01*
X814119Y551740D01*
X814122Y551744D01*
G02X816250Y549628I1115J-1007D01*
G01X813872Y547250D01*
G02X811747Y549369I-1109J1013D01*
G37*
G36*
G01X755247D02*
X755250Y549372D01*
X757619Y551740D01*
X757622Y551744D01*
G02X759750Y549628I1115J-1007D01*
G01X757372Y547250D01*
G02X755247Y549369I-1109J1013D01*
G37*
G36*
G01X838879Y547866D02*
X838882Y547869D01*
X841251Y550237D01*
X841254Y550241D01*
G02X843382Y548125I1115J-1007D01*
G01X841004Y545747D01*
G02X838879Y547866I-1109J1013D01*
G37*
G36*
G01X674511Y545936D02*
X672133Y543558D01*
G02X670008Y545677I-1109J1013D01*
G01X670011Y545680D01*
X672380Y548048D01*
X672383Y548052D01*
G02X674511Y545936I1115J-1007D01*
G37*
G36*
G01X683802Y544118D02*
X683805Y544121D01*
X686174Y546489D01*
X686177Y546493D01*
G02X688305Y544377I1115J-1007D01*
G01X685927Y541999D01*
G02X683802Y544118I-1109J1013D01*
G37*
G36*
G01X661408Y540365D02*
X659030Y537987D01*
G02X656905Y540106I-1109J1013D01*
G01X656908Y540109D01*
X659277Y542477D01*
X659280Y542481D01*
G02X661408Y540365I1115J-1007D01*
G37*
G36*
G01X723963Y522019D02*
X720609D01*
G02Y525019I-73J1500D01*
G01X723963D01*
G02Y522019I73J-1500D01*
G37*
G36*
G01X473172Y173420D02*
Y169100D01*
X473180Y169072D01*
G02X469340I-1920J-568D01*
G01X469348Y169100D01*
Y173420D01*
X469340Y173448D01*
G02X473180I1920J568D01*
G01X473172Y173420D01*
G37*
G36*
G01X466084Y149798D02*
Y145478D01*
X466093Y145450D01*
G02X462253I-1920J-568D01*
G01X462262Y145478D01*
Y149798D01*
X462253Y149826D01*
G02X466093I1920J568D01*
G01X466084Y149798D01*
G37*
G36*
G01X451912D02*
Y145478D01*
X451920Y145450D01*
G02X448080I-1920J-568D01*
G01X448088Y145478D01*
Y149798D01*
X448080Y149826D01*
G02X451920I1920J568D01*
G01X451912Y149798D01*
G37*
G36*
G01X437738D02*
Y145478D01*
X437747Y145450D01*
G02X433907I-1920J-568D01*
G01X433916Y145478D01*
Y149798D01*
X433907Y149826D01*
G02X437747I1920J568D01*
G01X437738Y149798D01*
G37*
G36*
G01X423564D02*
Y145478D01*
X423573Y145450D01*
G02X419733I-1920J-568D01*
G01X419742Y145478D01*
Y149798D01*
X419733Y149826D01*
G02X423573I1920J568D01*
G01X423564Y149798D01*
G37*
G36*
G01X473172Y145074D02*
Y140754D01*
X473180Y140726D01*
G02X469340I-1920J-568D01*
G01X469348Y140754D01*
Y145074D01*
X469340Y145102D01*
G02X473180I1920J568D01*
G01X473172Y145074D01*
G37*
G36*
G01X458998D02*
Y140754D01*
X459006Y140726D01*
G02X455166I-1920J-568D01*
G01X455174Y140754D01*
Y145074D01*
X455166Y145102D01*
G02X459006I1920J568D01*
G01X458998Y145074D01*
G37*
G36*
G01X444824D02*
Y140754D01*
X444833Y140726D01*
G02X440993I-1920J-568D01*
G01X441002Y140754D01*
Y145074D01*
X440993Y145102D01*
G02X444833I1920J568D01*
G01X444824Y145074D01*
G37*
G36*
G01X430652D02*
Y140754D01*
X430660Y140726D01*
G02X426820I-1920J-568D01*
G01X426828Y140754D01*
Y145074D01*
X426820Y145102D01*
G02X430660I1920J568D01*
G01X430652Y145074D01*
G37*
G36*
G01X466084Y135625D02*
Y131305D01*
X466093Y131277D01*
G02X462253I-1920J-568D01*
G01X462262Y131305D01*
Y135625D01*
X462253Y135653D01*
G02X466093I1920J568D01*
G01X466084Y135625D01*
G37*
G36*
G01X451912D02*
Y131305D01*
X451920Y131277D01*
G02X448080I-1920J-568D01*
G01X448088Y131305D01*
Y135625D01*
X448080Y135653D01*
G02X451920I1920J568D01*
G01X451912Y135625D01*
G37*
G36*
G01X437738D02*
Y131305D01*
X437747Y131277D01*
G02X433907I-1920J-568D01*
G01X433916Y131305D01*
Y135625D01*
X433907Y135653D01*
G02X437747I1920J568D01*
G01X437738Y135625D01*
G37*
G36*
G01X423564D02*
Y131305D01*
X423573Y131277D01*
G02X419733I-1920J-568D01*
G01X419742Y131305D01*
Y135625D01*
X419733Y135653D01*
G02X423573I1920J568D01*
G01X423564Y135625D01*
G37*
G36*
G01X473172Y130900D02*
Y126581D01*
X473180Y126553D01*
G02X469340I-1920J-568D01*
G01X469348Y126581D01*
Y130900D01*
X469340Y130928D01*
G02X473180I1920J568D01*
G01X473172Y130900D01*
G37*
G36*
G01X458998D02*
Y126581D01*
X459006Y126553D01*
G02X455166I-1920J-568D01*
G01X455174Y126581D01*
Y130900D01*
X455166Y130928D01*
G02X459006I1920J568D01*
G01X458998Y130900D01*
G37*
G36*
G01X444824D02*
Y126581D01*
X444833Y126553D01*
G02X440993I-1920J-568D01*
G01X441002Y126581D01*
Y130900D01*
X440993Y130928D01*
G02X444833I1920J568D01*
G01X444824Y130900D01*
G37*
G36*
G01X430652D02*
Y126581D01*
X430660Y126553D01*
G02X426820I-1920J-568D01*
G01X426828Y126581D01*
Y130900D01*
X426820Y130928D01*
G02X430660I1920J568D01*
G01X430652Y130900D01*
G37*
G36*
G01X529864Y173420D02*
Y169100D01*
X529873Y169072D01*
G02X526033I-1920J-568D01*
G01X526042Y169100D01*
Y173420D01*
X526033Y173448D01*
G02X529873I1920J568D01*
G01X529864Y173420D01*
G37*
G36*
G01X522778Y149798D02*
Y145478D01*
X522786Y145450D01*
G02X518946I-1920J-568D01*
G01X518954Y145478D01*
Y149798D01*
X518946Y149826D01*
G02X522786I1920J568D01*
G01X522778Y149798D01*
G37*
G36*
G01X508604D02*
Y145478D01*
X508613Y145450D01*
G02X504773I-1920J-568D01*
G01X504782Y145478D01*
Y149798D01*
X504773Y149826D01*
G02X508613I1920J568D01*
G01X508604Y149798D01*
G37*
G36*
G01X529864Y145074D02*
Y140754D01*
X529873Y140726D01*
G02X526033I-1920J-568D01*
G01X526042Y140754D01*
Y145074D01*
X526033Y145102D01*
G02X529873I1920J568D01*
G01X529864Y145074D01*
G37*
G36*
G01X515690D02*
Y140754D01*
X515699Y140726D01*
G02X511859I-1920J-568D01*
G01X511868Y140754D01*
Y145074D01*
X511859Y145102D01*
G02X515699I1920J568D01*
G01X515690Y145074D01*
G37*
G36*
G01X522778Y135625D02*
Y131305D01*
X522786Y131277D01*
G02X518946I-1920J-568D01*
G01X518954Y131305D01*
Y135625D01*
X518946Y135653D01*
G02X522786I1920J568D01*
G01X522778Y135625D01*
G37*
G36*
G01X508604D02*
Y131305D01*
X508613Y131277D01*
G02X504773I-1920J-568D01*
G01X504782Y131305D01*
Y135625D01*
X504773Y135653D01*
G02X508613I1920J568D01*
G01X508604Y135625D01*
G37*
G36*
G01X529864Y130900D02*
Y126581D01*
X529873Y126553D01*
G02X526033I-1920J-568D01*
G01X526042Y126581D01*
Y130900D01*
X526033Y130928D01*
G02X529873I1920J568D01*
G01X529864Y130900D01*
G37*
G36*
G01X515690D02*
Y126581D01*
X515699Y126553D01*
G02X511859I-1920J-568D01*
G01X511868Y126581D01*
Y130900D01*
X511859Y130928D01*
G02X515699I1920J568D01*
G01X515690Y130900D01*
G37*
G36*
G01X509942Y101692D02*
X505815D01*
G02Y104696I-36J1502D01*
G01X509945D01*
G02Y101692I36J-1502D01*
G01X509942D01*
G37*
G36*
G01X558210Y173420D02*
Y169100D01*
X558219Y169072D01*
G02X554379I-1920J-568D01*
G01X554388Y169100D01*
Y173420D01*
X554379Y173448D01*
G02X558219I1920J568D01*
G01X558210Y173420D01*
G37*
G36*
G01X551124Y149798D02*
Y145478D01*
X551132Y145450D01*
G02X547292I-1920J-568D01*
G01X547300Y145478D01*
Y149798D01*
X547292Y149826D01*
G02X551132I1920J568D01*
G01X551124Y149798D01*
G37*
G36*
G01X536950D02*
Y145478D01*
X536959Y145450D01*
G02X533119I-1920J-568D01*
G01X533128Y145478D01*
Y149798D01*
X533119Y149826D01*
G02X536959I1920J568D01*
G01X536950Y149798D01*
G37*
G36*
G01X558210Y145074D02*
Y140754D01*
X558219Y140726D01*
G02X554379I-1920J-568D01*
G01X554388Y140754D01*
Y145074D01*
X554379Y145102D01*
G02X558219I1920J568D01*
G01X558210Y145074D01*
G37*
G36*
G01X544038D02*
Y140754D01*
X544046Y140726D01*
G02X540206I-1920J-568D01*
G01X540214Y140754D01*
Y145074D01*
X540206Y145102D01*
G02X544046I1920J568D01*
G01X544038Y145074D01*
G37*
G36*
G01X551124Y135625D02*
Y131305D01*
X551132Y131277D01*
G02X547292I-1920J-568D01*
G01X547300Y131305D01*
Y135625D01*
X547292Y135653D01*
G02X551132I1920J568D01*
G01X551124Y135625D01*
G37*
G36*
G01X536950D02*
Y131305D01*
X536959Y131277D01*
G02X533119I-1920J-568D01*
G01X533128Y131305D01*
Y135625D01*
X533119Y135653D01*
G02X536959I1920J568D01*
G01X536950Y135625D01*
G37*
G36*
G01X558210Y130900D02*
Y126581D01*
X558219Y126553D01*
G02X554379I-1920J-568D01*
G01X554388Y126581D01*
Y130900D01*
X554379Y130928D01*
G02X558219I1920J568D01*
G01X558210Y130900D01*
G37*
G36*
G01X544038D02*
Y126581D01*
X544046Y126553D01*
G02X540206I-1920J-568D01*
G01X540214Y126581D01*
Y130900D01*
X540206Y130928D01*
G02X544046I1920J568D01*
G01X544038Y130900D01*
G37*
G54D51*
X305906Y182874D03*
G54D49*
X201801Y684252D03*
X225601D03*
G54D52*
X305906Y388386D03*
G54D56*
X666929Y510236D03*
X765354D03*
G54D57*
X745669D03*
X844094D03*
G54D53*
X811024Y24409D03*
G54D43*
X103346Y34449D03*
X56102Y24606D03*
G54D55*
X706299Y201771D03*
Y83661D03*
G54D54*
X804724Y201772D03*
Y83661D03*
G54D46*
X34652Y111485D03*
X899219Y47960D03*
G54D58*
X488838Y137225D03*
G54D59*
Y164744D03*
G54D47*
X90157Y413582D03*
X309055Y157677D03*
G54D50*
X309252Y413583D03*
G54D44*
X89764Y238386D03*
G54D45*
X70866Y98425D03*
X405512Y39370D03*
X875984Y31496D03*
Y472441D03*
Y606299D03*
G54D48*
X163189Y669291D03*
G54D27*
X339331Y49803D03*
X360669Y91929D03*
G54D12*
X38500Y56500D03*
X46500Y48500D03*
X28123Y453658D03*
X62276Y550493D03*
X37660Y566400D03*
X64427Y538836D03*
X67853Y558117D03*
X64701Y564416D03*
X28782Y555119D03*
X34132Y521245D03*
X34175Y526969D03*
X29165Y532612D03*
X29058Y538228D03*
X29158Y543855D03*
X28800Y549474D03*
X33697Y560866D03*
X61100Y546700D03*
X64277Y502177D03*
X67852Y539219D03*
X67853Y564416D03*
Y554967D03*
Y542368D03*
X42597Y571789D03*
X67852Y583313D03*
X67853Y573865D03*
X67852Y586463D03*
X64701Y570716D03*
X53302Y567317D03*
X58926Y582407D03*
X28667Y634097D03*
X42550Y599224D03*
X50400Y663700D03*
X50500Y667900D03*
X64884Y650984D03*
X37961Y659909D03*
X41100Y671800D03*
X86268Y58755D03*
X78268Y66755D03*
X121233Y450900D03*
X104000Y475500D03*
X118197Y490300D03*
X140490Y488605D03*
X132777Y462639D03*
X130787Y479138D03*
X113300Y448564D03*
X118065Y448535D03*
X100600Y490750D03*
X138023Y456188D03*
X140985Y454250D03*
X135262Y475726D03*
X105350Y511850D03*
X89899Y564415D03*
X119400Y511500D03*
X135012Y510200D03*
X94473Y547093D03*
X106272Y547370D03*
X89899Y558115D03*
X138900Y525999D03*
X136974Y534479D03*
X120500Y504600D03*
X69904Y502077D03*
X75399Y502179D03*
X81094Y502166D03*
X86699Y502300D03*
X97926D03*
X74151Y545516D03*
X86750Y542368D03*
X126337Y554085D03*
X74498Y551757D03*
X130311Y546700D03*
X71002Y539219D03*
X81276Y548766D03*
X119605Y548705D03*
X86750Y539218D03*
X74076Y535966D03*
X83600Y545518D03*
X75508Y542198D03*
X89899Y545518D03*
X127300Y543200D03*
X71002Y542368D03*
X117200Y546300D03*
X89899Y539218D03*
X83600Y539219D03*
X71002Y545518D03*
X86750D03*
X122600Y557480D03*
X71002Y558117D03*
X86750Y554965D03*
Y558115D03*
X83600Y551817D03*
X71002Y564396D03*
Y561266D03*
X83600Y564415D03*
X86750D03*
X75066Y563235D03*
X83600Y561265D03*
X71002Y554967D03*
X86750Y551815D03*
X133800Y528500D03*
X102601Y507300D03*
X123200Y534600D03*
X78276Y545566D03*
X93744Y542019D03*
X133554Y537374D03*
X71002Y548668D03*
X96371Y534124D03*
X125400Y498600D03*
X140400Y607850D03*
X137000D03*
X130700D03*
X135706Y621187D03*
X119900Y621000D03*
X131200Y620600D03*
X108371Y577258D03*
X86750Y567565D03*
X89901Y587466D03*
X93048Y577014D03*
X86750Y573864D03*
X89899D03*
X71002Y577013D03*
X85400Y629784D03*
X75197Y572437D03*
X130607Y569636D03*
X126347Y569556D03*
X117400Y567650D03*
X83600Y573865D03*
X74152Y567565D03*
X86750Y586463D03*
X71002Y567565D03*
X86750Y583313D03*
X74152Y580163D03*
X83601Y580164D03*
X89899Y577014D03*
X74152Y577013D03*
X86750Y577014D03*
X96570Y581730D03*
X124903Y613900D03*
X124793Y617299D03*
X139500Y611200D03*
X138970Y632277D03*
X128700Y615500D03*
X138700Y636655D03*
X103098Y620264D03*
X98537Y601094D03*
X102509Y601100D03*
X103109Y608572D03*
X103124Y605153D03*
X103098Y612064D03*
Y624364D03*
X113672Y605134D03*
X113512Y613401D03*
X113426Y609234D03*
X108137Y615870D03*
X113400Y621400D03*
Y617400D03*
X70700Y629000D03*
X133835Y609620D03*
X127100Y647000D03*
X123100D03*
X119000D03*
X73427Y699285D03*
X104550Y647050D03*
X104850Y639150D03*
X111300Y705500D03*
X86028Y696439D03*
X81928Y697539D03*
X106879Y707245D03*
X125376Y701124D03*
X106635Y701465D03*
X131300Y650100D03*
X135000Y650000D03*
X89868Y689124D03*
X121300Y651900D03*
X139774Y666686D03*
X119849Y709715D03*
X106355Y710745D03*
X148000Y469000D03*
X196100Y482200D03*
X170870Y492270D03*
X186254Y463761D03*
X181200Y489451D03*
X155710Y485200D03*
X172300Y478400D03*
X172900Y484101D03*
X169252Y483871D03*
X213159Y460326D03*
X154334Y465100D03*
X149000Y488600D03*
X171537Y464400D03*
X179100Y455800D03*
X201600Y486500D03*
X198200D03*
X190036Y485520D03*
X194411Y485447D03*
X163031Y441700D03*
X193400Y463300D03*
X153489Y481559D03*
X148490Y451286D03*
X144245Y452344D03*
X151877Y450439D03*
X155877D03*
X145000Y488600D03*
X167680Y510640D03*
X166761Y498900D03*
X198700Y513500D03*
X203350Y506700D03*
X188600Y531500D03*
X179000Y499800D03*
X203500Y513500D03*
X191398Y509000D03*
X211700Y513500D03*
X208700Y529100D03*
X207500Y502412D03*
X145000Y497600D03*
X203610Y529397D03*
X179400Y525100D03*
X182964Y510414D03*
X154400Y533500D03*
X187100Y509600D03*
X195200Y513200D03*
X162537Y499000D03*
X160286Y508429D03*
X183750Y524200D03*
X143415Y530143D03*
X171200Y509840D03*
X170800Y499800D03*
X166600Y524100D03*
X144087Y526413D03*
X176900Y496500D03*
X174717Y524010D03*
X178869Y509793D03*
X200650Y497862D03*
X199501Y509275D03*
X191200Y522500D03*
X191300Y525900D03*
X174700Y509600D03*
X207500Y505812D03*
X158000Y499000D03*
X200200Y529200D03*
X156000Y496100D03*
X203696Y533000D03*
X156200Y535800D03*
X188834Y496920D03*
X190929Y512592D03*
X150553Y512500D03*
X148050Y523740D03*
X196800Y497862D03*
X193200Y497000D03*
X174400Y519283D03*
X200963Y636600D03*
X212923Y615000D03*
X191210Y617900D03*
X203300Y628900D03*
X148409Y575672D03*
X144876Y590854D03*
X148409Y579353D03*
X144876Y587173D03*
X197611Y630698D03*
X193400Y630600D03*
X174799Y630303D03*
X171400Y630200D03*
X199950Y614000D03*
X196100Y614050D03*
X203900Y614100D03*
X144737Y630882D03*
X200100Y633300D03*
X209193Y614249D03*
X162750Y612217D03*
X164400Y609200D03*
X182100Y629800D03*
X178200D03*
X148210Y629830D03*
X141742Y624666D03*
X144263Y609023D03*
X151800Y610300D03*
X188899Y629597D03*
X185500Y629700D03*
X154500Y629600D03*
X195600Y646000D03*
X166500Y640300D03*
X191766Y679920D03*
X211706Y645349D03*
X208200Y645500D03*
X148249Y695765D03*
X151130Y703440D03*
X184807Y643963D03*
X188500Y686800D03*
X151949Y691715D03*
X176447Y704925D03*
X162700Y703500D03*
X150849Y710215D03*
X162360Y706888D03*
X168273Y696434D03*
X158994Y694545D03*
X205800Y698400D03*
X210123Y662100D03*
X200000Y664200D03*
X204100Y646500D03*
X199600Y646300D03*
X195500Y696900D03*
X207000Y654400D03*
X185598Y709274D03*
X182200Y709400D03*
X143174Y666586D03*
X162100Y711215D03*
X275276Y494017D03*
X213900Y474650D03*
X227100Y490300D03*
X275300Y467300D03*
X277455Y446150D03*
X226475Y480400D03*
X254100Y440800D03*
X257950Y440600D03*
X226500Y477000D03*
X275113Y476513D03*
X266664Y493000D03*
X214808Y463300D03*
X231400Y489800D03*
X237903D03*
X267670Y485870D03*
X271100Y485900D03*
X222995Y443805D03*
X240900Y440900D03*
X236400Y440800D03*
X280600Y448900D03*
X214900Y490000D03*
X231476Y449662D03*
X276591Y483709D03*
X245874Y458478D03*
X242500Y458900D03*
X253400Y453500D03*
X273400Y449700D03*
X249465Y458000D03*
X252626Y469150D03*
X244400Y478600D03*
X244300Y474150D03*
X225532Y450047D03*
X237600Y455500D03*
X233664Y482859D03*
X226607Y444058D03*
X230610Y444055D03*
X234648Y540453D03*
X221960Y504230D03*
X222500Y536161D03*
X279600Y527900D03*
X233850Y552201D03*
X234943Y565199D03*
X260513Y564135D03*
X265100Y562300D03*
X227600Y563000D03*
X254494Y529198D03*
X248459Y523892D03*
X269100Y509063D03*
X244850Y540150D03*
X248700Y540000D03*
X228200Y496200D03*
X263600Y540700D03*
X226357Y504514D03*
X257894Y529254D03*
X263600Y535350D03*
X223800Y531600D03*
X236400Y502150D03*
X246508Y532821D03*
X228100Y545500D03*
X227100Y525400D03*
X228800Y542100D03*
X238600Y509900D03*
X228313Y552169D03*
X233100Y509800D03*
X275100D03*
X260900Y553900D03*
X242600Y509800D03*
X233607Y557671D03*
X241154Y536017D03*
X250445Y548551D03*
X255800Y539600D03*
X279200Y531600D03*
X250400Y636976D03*
X215800Y631200D03*
X260705Y598359D03*
X232896Y613795D03*
X279450Y577970D03*
X260850Y603537D03*
X274800Y607500D03*
X258600Y613100D03*
X254208Y603995D03*
X254043Y598359D03*
X247088Y610236D03*
X254821Y627000D03*
X255228Y631071D03*
X278150Y637250D03*
X229800Y593200D03*
X246800Y589600D03*
X261900Y588900D03*
X245400Y581800D03*
X264358Y608152D03*
X241300Y635900D03*
X228900Y635800D03*
X222500Y630200D03*
X218800Y635600D03*
X225900Y615000D03*
X221800Y614800D03*
X246500Y602500D03*
X234000Y628400D03*
X230900Y581600D03*
X270300Y622315D03*
X281500Y598419D03*
X242333Y593800D03*
X257346Y599169D03*
X257332Y602569D03*
X258398Y605915D03*
Y609484D03*
X218200Y609500D03*
X262694Y568076D03*
X261300Y571300D03*
X235800Y615100D03*
X233447Y603747D03*
X232300Y600300D03*
X258596Y586356D03*
X259848Y583194D03*
X279214Y591383D03*
X275652Y577455D03*
X237100Y590000D03*
X234087Y618038D03*
X248800Y582000D03*
X273022Y580751D03*
X268200Y578700D03*
X259000Y617000D03*
X234800Y572000D03*
X256007Y575050D03*
X281975Y572963D03*
X279800Y569182D03*
X264200Y574100D03*
X261810Y633980D03*
X264800Y632300D03*
X276783Y588907D03*
X258873Y631373D03*
X215400Y626800D03*
X281510Y583003D03*
X276400Y700650D03*
X254900Y701950D03*
X267500Y645600D03*
X280500Y708100D03*
X269003Y704337D03*
X282620Y640950D03*
X262826Y662274D03*
X245100Y639500D03*
X219200Y645300D03*
X230270Y645933D03*
X247725Y656375D03*
X261900Y699300D03*
X266550Y675750D03*
X247825Y670375D03*
X245971Y698400D03*
X235100Y679921D03*
X221575Y695400D03*
X279400Y686400D03*
X223013Y645672D03*
X272300Y665700D03*
X266398Y679250D03*
X226708Y645869D03*
X239400Y677600D03*
X267045Y695881D03*
X215606Y645300D03*
X277600Y680200D03*
X217638Y695562D03*
X239000Y691000D03*
X276400Y697250D03*
X254700Y708900D03*
X271220Y679910D03*
X255000Y679900D03*
X235042Y656173D03*
X263500Y643212D03*
X243100Y677500D03*
X267100Y699700D03*
X266400Y662200D03*
X280600Y711700D03*
X282353Y740020D03*
X268820Y715100D03*
X262645Y712155D03*
X268230Y723570D03*
X345069Y108533D03*
X340080Y108432D03*
X348900Y115400D03*
X340706Y128612D03*
X352000Y109000D03*
X355500D03*
X305703Y202696D03*
X306407Y206057D03*
X355300Y179300D03*
X354282Y187718D03*
Y191718D03*
X305651Y199283D03*
X294720Y182200D03*
X320700Y177800D03*
X294720Y178600D03*
Y185600D03*
X307567Y277592D03*
Y273592D03*
X304548Y272508D03*
Y268508D03*
Y265008D03*
Y261008D03*
X321432Y279090D03*
X321281Y266486D03*
X321197Y254433D03*
X306446Y247874D03*
X323842Y219284D03*
X305498Y213824D03*
X305382Y227474D03*
X323800Y227000D03*
X323700Y230600D03*
X333882Y273978D03*
Y270578D03*
X335098Y233078D03*
X305782Y230874D03*
X334482Y263778D03*
X333782Y267178D03*
X324000Y222800D03*
X305782Y220674D03*
X305682Y224074D03*
X305782Y217274D03*
X334198Y248824D03*
X305454Y244461D03*
X334282Y252378D03*
X305373Y251101D03*
X306412Y254339D03*
X334260Y255820D03*
X305882Y234274D03*
X305772Y237673D03*
X305781Y241076D03*
X334107Y291354D03*
Y287354D03*
Y283854D03*
Y279854D03*
X307567Y349192D03*
X304267Y348092D03*
Y344092D03*
Y340592D03*
Y336592D03*
X307567Y335492D03*
Y331492D03*
Y327992D03*
Y323992D03*
X304267Y322892D03*
Y318892D03*
Y315392D03*
Y311392D03*
X307567Y310292D03*
Y306292D03*
Y302792D03*
Y298792D03*
X304267Y297692D03*
Y293692D03*
Y290192D03*
Y286192D03*
X334582Y341721D03*
Y337721D03*
Y334221D03*
Y330221D03*
X328187Y350316D03*
Y346816D03*
Y342816D03*
X328182Y329124D03*
Y325124D03*
Y321624D03*
Y317624D03*
X334593Y316584D03*
Y312584D03*
Y309084D03*
Y305084D03*
X328182Y303977D03*
Y299977D03*
Y296477D03*
Y292477D03*
X307567Y285092D03*
Y281092D03*
X321432Y342082D03*
Y329484D03*
Y316885D03*
X321882Y304374D03*
Y291874D03*
X304267Y373292D03*
Y369292D03*
Y365792D03*
Y361792D03*
X307567Y360692D03*
Y356692D03*
Y353192D03*
X328182Y379518D03*
Y375518D03*
Y372018D03*
Y368018D03*
X334582Y366974D03*
Y362974D03*
Y359474D03*
Y355474D03*
X328187Y354316D03*
X320832Y367479D03*
X321432Y354681D03*
X320932Y377074D03*
X340606Y389899D03*
X350408Y393708D03*
X348006Y391300D03*
X321859Y388315D03*
X321100Y384874D03*
X346300Y374600D03*
X349100Y379100D03*
X303900Y380574D03*
X348997Y491678D03*
X295700Y428400D03*
X293326Y494174D03*
X344900Y442800D03*
X344688Y493896D03*
X343050Y438900D03*
X339900Y454000D03*
X328313Y435513D03*
X324916Y435360D03*
X321700Y436650D03*
X296254Y546706D03*
X305350Y514300D03*
X292200Y542473D03*
X285800Y549394D03*
X346440Y527500D03*
X350879Y520400D03*
X352734Y541826D03*
X355700Y510000D03*
X344600Y511800D03*
X326900Y507700D03*
X304800Y554443D03*
X318200Y522900D03*
X285833Y557629D03*
X293600Y518400D03*
X288000Y561000D03*
X313300Y518800D03*
X354300Y500245D03*
X288311Y496200D03*
X355600Y506600D03*
X298200Y521100D03*
X301300Y524400D03*
X355600Y513500D03*
X327300Y540100D03*
X341400Y560050D03*
X336881Y530496D03*
X307800Y546700D03*
X341615Y556015D03*
X336953Y534506D03*
X305913Y549643D03*
X331900Y549700D03*
X329050Y552315D03*
X348220Y563836D03*
X344812Y563844D03*
X344755Y497841D03*
X304436Y564081D03*
X341349Y563750D03*
X307350Y561290D03*
X335000Y497000D03*
X332698Y543738D03*
X330200Y535200D03*
X331000Y522100D03*
X302665Y547006D03*
X302506Y543341D03*
X327403Y543499D03*
X336723Y542000D03*
X327800Y514900D03*
X330200Y531800D03*
X323400Y507540D03*
X336800Y506300D03*
X286061Y502378D03*
X293970Y564927D03*
X335000Y500600D03*
X298719Y542538D03*
X293500Y522600D03*
X334811Y551476D03*
X311900Y511500D03*
X309600Y520150D03*
X312300Y540600D03*
X332940Y539287D03*
X333400Y503800D03*
X322900Y530600D03*
X327417Y548344D03*
X290000Y503200D03*
X293800Y503300D03*
X299100Y589200D03*
X304124Y570227D03*
X341750Y630790D03*
X342330Y620300D03*
X344940Y617720D03*
X292400Y637000D03*
X341690Y609930D03*
X341210Y602420D03*
X330800Y602610D03*
X317572Y603183D03*
X305470Y623734D03*
X307542Y588138D03*
X334923Y579949D03*
X355700Y579317D03*
X341755Y627231D03*
Y623682D03*
X341600Y616962D03*
Y613413D03*
X334264Y602648D03*
X337813D03*
X352716Y594135D03*
X350746Y574837D03*
X293500Y625600D03*
X293600Y629100D03*
X321421Y605265D03*
X323413Y602491D03*
X303000Y586800D03*
X292006Y574797D03*
X315616Y571817D03*
X289800Y569182D03*
X315893Y567721D03*
X341558Y567689D03*
X300043Y603619D03*
X303468Y603647D03*
X352716Y590535D03*
X347784Y587509D03*
X336923Y586749D03*
X347784Y584109D03*
X336923Y583349D03*
X307650Y596000D03*
X285400Y572556D03*
X325761Y592959D03*
X315315Y575204D03*
X317813Y580469D03*
X286400Y569200D03*
X317813Y584969D03*
X325899Y589186D03*
X297118Y668882D03*
X294804Y695204D03*
X292400Y640500D03*
X332824Y684270D03*
X348314Y643853D03*
X332800Y691970D03*
X318000Y678270D03*
X304100Y666500D03*
X351547Y645938D03*
X355100Y651827D03*
X314398Y670254D03*
X340000Y662200D03*
X353700Y670900D03*
X352800Y702960D03*
X290600Y668200D03*
X338301Y673907D03*
X328600Y661100D03*
X343372Y655836D03*
X347013Y656090D03*
X328087Y701587D03*
X327062Y697600D03*
X332200Y643800D03*
X288720Y641455D03*
X289473Y657061D03*
X336000Y662200D03*
X336387Y648987D03*
X317516Y671612D03*
X315000Y674900D03*
X338135Y670511D03*
X342542Y685983D03*
X342645Y682506D03*
X300700Y667000D03*
X330593Y671019D03*
X303741Y654095D03*
X329989Y653920D03*
X298570Y743670D03*
X306470Y743570D03*
X287220Y737920D03*
X334000Y714640D03*
X293075Y726600D03*
X342208Y714950D03*
X337481Y719818D03*
X380500Y33500D03*
Y30000D03*
X382631Y48200D03*
X382547Y52800D03*
X375300Y62150D03*
X384000Y30000D03*
X425765Y56265D03*
X372500Y44500D03*
Y56500D03*
X375300Y72050D03*
X357500Y104200D03*
X394070Y80840D03*
X385964Y80089D03*
X382500Y88000D03*
X376000Y78400D03*
X366500Y124700D03*
X363100Y124600D03*
X387833Y82930D03*
X391382D03*
X372500Y90000D03*
Y78000D03*
X396800Y74800D03*
X405100Y159300D03*
X400000Y159200D03*
X365900Y198500D03*
X399900Y152100D03*
X400924Y155896D03*
X404473D03*
X398000Y165400D03*
X398050Y162000D03*
X406400Y150300D03*
X362150Y214174D03*
X364000Y240100D03*
X381009Y343909D03*
X380799Y347303D03*
X386250Y318250D03*
X380600Y335700D03*
X373700Y329700D03*
X376910Y366078D03*
X359323Y372277D03*
X363699Y382608D03*
X363703Y386008D03*
X363586Y375809D03*
X363701Y379208D03*
X377300Y362700D03*
X379448Y487250D03*
X363942Y450591D03*
X366700Y454800D03*
X359400Y451600D03*
X381276Y469106D03*
X374030Y449526D03*
X372575Y452600D03*
X380200Y457800D03*
X381400Y462000D03*
X387500Y458200D03*
X370800Y475128D03*
X389081Y475224D03*
X387950Y466800D03*
X394700Y481700D03*
X394952Y485300D03*
X378937Y443491D03*
X376697Y446050D03*
X373576Y466300D03*
X373534Y462830D03*
X370900Y471700D03*
X373700Y482700D03*
X378200Y476600D03*
X377691Y451891D03*
X381370Y465500D03*
X388123Y492432D03*
X378840Y448690D03*
X361013Y475128D03*
X368100Y513100D03*
X387800Y529400D03*
X367500Y526800D03*
X393100Y564400D03*
X362801Y548097D03*
X366900Y499942D03*
X384400Y545195D03*
X362666Y504265D03*
X390651Y499000D03*
X387800Y525500D03*
X387700Y521600D03*
X376617Y544817D03*
X397650Y508250D03*
Y536671D03*
X362280Y554590D03*
X397650Y519400D03*
X394880Y548670D03*
X397650Y523900D03*
X393465Y553100D03*
X387700Y517700D03*
X362500Y499970D03*
X365730Y541050D03*
X368900Y505000D03*
X372494Y513020D03*
X383126Y565162D03*
X366490Y564360D03*
X370763Y547900D03*
X370800Y551300D03*
Y554700D03*
X383080Y554897D03*
X384347Y558647D03*
X382922Y561735D03*
X372900Y538700D03*
X396400Y545500D03*
X390769Y495379D03*
X393889Y543207D03*
X396200Y597200D03*
X394800Y609700D03*
X358646Y596456D03*
X359000Y635600D03*
X360980Y582586D03*
X394300Y576600D03*
X372951Y576851D03*
X377714Y631280D03*
X368399Y567372D03*
X364300Y592900D03*
X384500Y616500D03*
X361227Y630300D03*
X378400Y594800D03*
X383313Y621780D03*
X365953Y570753D03*
X382600Y609000D03*
X375700Y580102D03*
X390600Y625500D03*
X366100Y590000D03*
X366500Y586300D03*
X380572Y592095D03*
X396300Y587000D03*
X396400Y583500D03*
X395127Y568056D03*
X395100Y572899D03*
X388418Y650549D03*
X385700Y641300D03*
X374200Y645871D03*
X374252Y641029D03*
X379100Y703300D03*
X363664Y688950D03*
X384466Y661650D03*
X378832Y659705D03*
X364600Y670800D03*
X388338Y643600D03*
Y647149D03*
X392100Y683900D03*
X392000Y679800D03*
X390500Y665800D03*
Y669200D03*
X396306Y698732D03*
X361914Y680181D03*
X401000Y676500D03*
X371457Y667593D03*
X368060Y667743D03*
X392079Y703434D03*
X396400Y659800D03*
X390355Y690926D03*
X373060Y702960D03*
X398600Y662700D03*
X383600Y711800D03*
X372100Y711700D03*
X478426Y20427D03*
X496394Y30000D03*
X482727Y41870D03*
X486535Y47449D03*
X482397Y52176D03*
X472800Y50000D03*
X469000Y50100D03*
X499721Y46102D03*
X499623Y49524D03*
X446788Y55180D03*
X479040Y47134D03*
X458041Y47341D03*
X476100Y60500D03*
X478700Y62800D03*
X462372Y49179D03*
X486400Y38500D03*
X467016Y20430D03*
X450454Y38147D03*
X486527Y41939D03*
X447233Y48829D03*
X496355Y26000D03*
X496242Y22287D03*
X460300Y57600D03*
X432269Y19980D03*
X486700Y31100D03*
X462874Y95922D03*
X487500Y73400D03*
X485700Y70500D03*
X448000Y80404D03*
X444800Y82404D03*
X478590Y70310D03*
X482200Y70500D03*
X498500Y84200D03*
X471281Y105681D03*
X455766Y114535D03*
X473600Y108300D03*
X457000Y117800D03*
X480538Y112071D03*
X459500Y95500D03*
X441100Y110950D03*
X448996Y117666D03*
X463479Y99412D03*
X504900Y18200D03*
X508646Y18386D03*
X518890Y59730D03*
X515700Y50899D03*
X515785Y55552D03*
X505633Y46932D03*
X502300Y58200D03*
X531050Y46998D03*
X528300Y58648D03*
X515500Y59000D03*
X532500Y58600D03*
X513379Y103325D03*
X502379Y103194D03*
X543059Y108958D03*
X540800Y111500D03*
X501100Y86800D03*
X509981Y103194D03*
X505779D03*
X513300Y83000D03*
X503700Y107600D03*
X599254Y37967D03*
X582447Y50607D03*
X588647Y28007D03*
X576649Y39585D03*
X575300Y45967D03*
X586754Y53967D03*
X577847Y50807D03*
X582797Y31807D03*
X600847Y33907D03*
X588753Y24080D03*
X603747Y71407D03*
X636647Y64300D03*
X642998Y127863D03*
X642574Y131843D03*
X685907Y30622D03*
X673647Y33107D03*
X680300Y17500D03*
X680000Y23900D03*
X675903Y29541D03*
X668531Y71500D03*
X713200Y387700D03*
X696070Y483486D03*
X712874Y470182D03*
X707391Y484208D03*
X712000Y442100D03*
X711300Y423800D03*
X701183Y453339D03*
X704836D03*
X709700Y480332D03*
X698651Y428165D03*
X669749Y458022D03*
X683000Y447200D03*
X680200Y449500D03*
X705450Y440950D03*
X705700Y493500D03*
X708367Y491000D03*
X708682Y551846D03*
X711156Y554320D03*
X699453Y551078D03*
X701927Y553552D03*
X686198Y552098D03*
X688672Y554572D03*
X684818Y543012D03*
X687292Y545486D03*
X671024Y544571D03*
X673498Y547045D03*
X657921Y539000D03*
X660395Y541474D03*
X653634Y513757D03*
X656846Y521702D03*
X678740Y508760D03*
X777500Y34500D03*
X766200Y22000D03*
X723800Y18600D03*
X718300Y387700D03*
X725200Y442100D03*
X740500Y431000D03*
X723800Y475164D03*
X788263Y554763D03*
X778763Y553763D03*
X781237Y556237D03*
X768263Y552763D03*
X770737Y555237D03*
X756263Y548263D03*
X758737Y550737D03*
X728682Y549946D03*
X731156Y552420D03*
X717829Y549856D03*
X720303Y552330D03*
X720536Y523519D03*
X724036D03*
X759342Y543603D03*
X765935Y537009D03*
X777165Y509835D03*
X854596Y155288D03*
X840122Y156614D03*
X843160Y169467D03*
X845168Y192764D03*
X851137Y199864D03*
X858622Y155614D03*
X854634Y166390D03*
X842022Y152174D03*
X858632Y216929D03*
X857700Y222300D03*
X848868Y219064D03*
X850730Y350483D03*
X841116Y348914D03*
X835316Y340914D03*
X846456Y350814D03*
X847720Y371072D03*
X831650Y422612D03*
X830531Y361589D03*
X794200Y422800D03*
X811300Y395900D03*
X801200Y386700D03*
X796100D03*
X821800Y400500D03*
X821700Y403900D03*
X842820Y382172D03*
X816997Y371022D03*
X847629Y391998D03*
X855320Y414472D03*
X830133Y353930D03*
X842916Y357214D03*
X849420Y407748D03*
X822300Y390000D03*
X811142Y470358D03*
X811668Y433703D03*
X820150Y433900D03*
X794900Y441100D03*
X808100D03*
X807400Y477229D03*
X823710Y469835D03*
X803300Y491600D03*
X806888Y491398D03*
X825263Y553263D03*
X827737Y555737D03*
X812763Y548263D03*
X815237Y550737D03*
X806763Y554763D03*
X809237Y557237D03*
X797763Y554263D03*
X800237Y556737D03*
X790737Y557237D03*
X842369Y549234D03*
X839895Y546760D03*
X867653Y172764D03*
X867851Y163585D03*
X864992Y175435D03*
X864492Y206435D03*
X860868Y219764D03*
X868433Y349134D03*
X864920Y368972D03*
X861420Y367269D03*
X861484Y399069D03*
G54D16*
X60600Y670900D03*
X65900Y671000D03*
X65714Y665850D03*
X60800Y660900D03*
X60700Y665900D03*
X65700Y660900D03*
X139916Y709422D03*
X130019Y709695D03*
X139916Y705822D03*
X130019Y706095D03*
X135019D03*
X70700Y671000D03*
X70800Y660700D03*
X70600Y665800D03*
X139916Y713022D03*
Y716622D03*
Y720222D03*
Y723822D03*
X130019Y713295D03*
Y716895D03*
Y720495D03*
X135019Y710595D03*
Y723595D03*
Y719095D03*
Y714845D03*
X130019Y724095D03*
X265400Y446100D03*
X312289Y535181D03*
X311386Y633450D03*
X306300Y638600D03*
X301286Y638650D03*
X301386Y633650D03*
X306286D03*
X311186Y638550D03*
X300720Y704920D03*
X300520Y710020D03*
X290620Y710120D03*
X295634Y710070D03*
X290720Y705120D03*
X295620D03*
X301186Y643650D03*
X306486Y643750D03*
X311286D03*
X300620Y715220D03*
X290520Y715120D03*
X295820Y715220D03*
X365164Y612620D03*
X358864D03*
X371400Y606400D03*
X358800Y606300D03*
X365300Y606500D03*
X371400Y612700D03*
X371300Y618800D03*
X365500Y619000D03*
X358900Y618800D03*
X468000Y31500D03*
Y39500D03*
X464000Y35500D03*
X468000Y35400D03*
X472000Y35500D03*
X603943Y42806D03*
X608143Y42906D03*
X603943Y47006D03*
X608043D03*
X753800Y535000D03*
X857020Y383172D03*
Y379572D03*
Y386772D03*
X875272Y186265D03*
X878872D03*
X860872D03*
X871672D03*
X868072D03*
X864472D03*
X878372Y191265D03*
X878872Y196265D03*
X864472D03*
X868072D03*
X871672D03*
X875272D03*
X865372Y191265D03*
X873872D03*
X869622D03*
X860872Y196265D03*
Y191265D03*
X871420Y383172D03*
X875020D03*
Y379572D03*
X871420D03*
X867820D03*
X860620D03*
X864220D03*
X875020Y386772D03*
X871420D03*
X867820D03*
X860620D03*
X864220D03*
X867820Y383172D03*
X860620D03*
X864220D03*
G54D24*
X201801Y684252D03*
X225601D03*
G54D31*
X421653Y130709D03*
X428740Y125985D03*
X421653Y136221D03*
X428740Y131496D03*
X421653Y144882D03*
X428740Y140158D03*
X421653Y150394D03*
X428740Y145670D03*
X421653Y159055D03*
X428740Y154331D03*
X421653Y164567D03*
X428740Y159843D03*
X421653Y173229D03*
X428740Y168504D03*
X421653Y178740D03*
X428740Y174016D03*
X435827Y130709D03*
X442913Y125985D03*
X450000Y130709D03*
X457086Y125985D03*
X464173Y130709D03*
X471260Y125985D03*
X435827Y136221D03*
X442913Y131496D03*
X450000Y136221D03*
X457086Y131496D03*
X464173Y136221D03*
X471260Y131496D03*
X435827Y144882D03*
X442913Y140158D03*
X450000Y144882D03*
X457086Y140158D03*
X464173Y144882D03*
X471260Y140158D03*
X435827Y150394D03*
X442913Y145670D03*
X450000Y150394D03*
X457086Y145670D03*
X464173Y150394D03*
X471260Y145670D03*
X435827Y159055D03*
X442913Y154331D03*
X450000Y159055D03*
X457086Y154331D03*
X464173Y159055D03*
X471260Y154331D03*
X435827Y164567D03*
X442913Y159843D03*
X450000Y164567D03*
X457086Y159843D03*
X464173Y164567D03*
X471260Y159843D03*
X435827Y173229D03*
X442913Y168504D03*
X450000Y173229D03*
X457086Y168504D03*
X464173Y173229D03*
X471260Y168504D03*
X435827Y178740D03*
X442913Y174016D03*
X450000Y178740D03*
X457086Y174016D03*
X464173Y178740D03*
X471260Y174016D03*
X506693Y126378D03*
X520866D03*
X513779Y121654D03*
X527953D03*
X506693Y130709D03*
X513779Y125985D03*
X520866Y130709D03*
X527953Y125985D03*
X535039Y130709D03*
X542126Y125985D03*
X549212Y130709D03*
X556299Y125985D03*
X506693Y136221D03*
X513779Y131496D03*
X520866Y136221D03*
X527953Y131496D03*
X535039Y136221D03*
X542126Y131496D03*
X549212Y136221D03*
X556299Y131496D03*
X513779Y135827D03*
X527953D03*
X506693Y183071D03*
X520866D03*
X506693Y140551D03*
X520866D03*
X506693Y144882D03*
X513779Y140158D03*
X520866Y144882D03*
X527953Y140158D03*
X535039Y144882D03*
X542126Y140158D03*
X549212Y144882D03*
X556299Y140158D03*
X506693Y150394D03*
X513779Y145670D03*
X520866Y150394D03*
X527953Y145670D03*
X535039Y150394D03*
X542126Y145670D03*
X549212Y150394D03*
X556299Y145670D03*
X506693Y154725D03*
X513779Y150000D03*
X520866Y154725D03*
X527953Y150000D03*
X513779Y154331D03*
X520866Y159055D03*
X527953Y154331D03*
X535039Y159055D03*
X542126Y154331D03*
X549212Y159055D03*
X556299Y154331D03*
X513779Y159843D03*
X520866Y164567D03*
X527953Y159843D03*
X535039Y164567D03*
X542126Y159843D03*
X549212Y164567D03*
X556299Y159843D03*
X506693Y168898D03*
X513779Y164173D03*
X520866Y168898D03*
X527953Y164173D03*
X513779Y168504D03*
X520866Y173229D03*
X527953Y168504D03*
X535039Y173229D03*
X542126Y168504D03*
X549212Y173229D03*
X556299Y168504D03*
X520866Y178740D03*
X527953Y174016D03*
X535039Y178740D03*
X542126Y174016D03*
X549212Y178740D03*
X556299Y174016D03*
G54D34*
X513779Y179528D03*
X527953D03*
G54D30*
X305906Y388386D03*
G54D20*
X103940Y635460D03*
X86300Y703200D03*
X99337Y683756D03*
Y678756D03*
Y673756D03*
X86300Y708000D03*
X95200Y667500D03*
X90400D03*
X85600D03*
X134223Y691027D03*
X122335Y660582D03*
Y655782D03*
X111395Y755266D03*
X116395D03*
X121395D03*
X126395D03*
X131395D03*
X136395D03*
X141395D03*
X108928Y744775D03*
X113928D03*
X118928D03*
X123928D03*
X103928D03*
X98928D03*
X196700Y704985D03*
X201700D03*
X206700D03*
X211700D03*
X191700D03*
X146395Y755266D03*
X151395D03*
X156395D03*
X161395D03*
X166395D03*
X171395D03*
X176395D03*
X181395D03*
X186395D03*
X191395D03*
X196395D03*
X201395D03*
X206395D03*
X211395D03*
X155400Y717700D03*
X221700Y704985D03*
X226700D03*
X216700D03*
X216395Y755266D03*
X221395D03*
X226395D03*
X231395D03*
X236395D03*
X241395D03*
X246395D03*
X251395D03*
X256395D03*
X261395D03*
X266395D03*
X271395D03*
X276395D03*
X281395D03*
X296034Y14002D03*
Y19002D03*
Y24002D03*
Y29002D03*
Y34002D03*
Y39002D03*
Y44002D03*
Y49002D03*
Y54002D03*
Y59002D03*
Y64002D03*
Y69002D03*
Y74002D03*
Y79002D03*
Y84002D03*
Y89002D03*
Y94002D03*
Y99002D03*
Y104002D03*
Y109002D03*
Y114002D03*
Y119002D03*
Y124002D03*
Y129002D03*
Y134002D03*
Y139002D03*
X334782Y184928D03*
X321182Y202574D03*
Y197774D03*
X334882Y195478D03*
Y200478D03*
Y190478D03*
X323492Y214234D03*
X305862Y210014D03*
X335000Y621200D03*
Y615400D03*
Y610200D03*
X325600Y640100D03*
X330400D03*
X335200D03*
X298700Y674600D03*
X303700D03*
X286395Y755266D03*
X291395D03*
X296395D03*
X301395D03*
X306395D03*
X311395D03*
X316395D03*
X321395D03*
X315520Y711720D03*
X320320D03*
X325120D03*
X435000Y29000D03*
X438500Y25500D03*
Y32500D03*
X556510Y53626D03*
X516693Y46345D03*
X521493D03*
X526530Y43775D03*
X567700Y28240D03*
X548550Y76480D03*
X525000Y76300D03*
X525200Y80900D03*
X556710Y64726D03*
X543750Y76480D03*
X608847Y34607D03*
X614032Y33307D03*
X621747Y63307D03*
X626647Y67507D03*
X593017Y69796D03*
X588217Y74596D03*
Y69796D03*
X668847Y27107D03*
X663847D03*
X658847D03*
X653847D03*
X649590Y114036D03*
X689875Y464586D03*
X698275Y438305D03*
X683100Y485200D03*
X679832Y494100D03*
Y489100D03*
X679100Y483300D03*
X674900D03*
X674832Y489100D03*
Y494100D03*
X682800Y480700D03*
X770065Y55985D03*
X736217Y493664D03*
X776658Y489380D03*
X771658D03*
X781658D03*
Y494380D03*
X741217Y493664D03*
X776658Y494380D03*
X771658D03*
X752602Y517850D03*
X736580Y507734D03*
X788015Y507785D03*
X783015D03*
X747602Y517850D03*
X731580Y507734D03*
X716578Y509762D03*
X721590Y511659D03*
X726590D03*
X853436Y108917D03*
Y113717D03*
X853435Y90260D03*
Y95060D03*
X857965Y273150D03*
X859407Y300314D03*
Y309914D03*
Y305114D03*
Y295314D03*
Y290314D03*
Y285314D03*
X809000Y429400D03*
X840057Y494320D03*
X835057D03*
X836023Y508124D03*
X825161Y507954D03*
X820161D03*
X815161D03*
X805983Y508293D03*
X793015Y507785D03*
X897250Y81510D03*
X902050D03*
Y86310D03*
X897250D03*
Y91110D03*
X902050D03*
X897250Y95910D03*
X902050D03*
X900600Y201239D03*
X897803Y207684D03*
X902803D03*
X880222Y206781D03*
X875222D03*
X897195Y275688D03*
X902195D03*
Y270688D03*
X897195D03*
X897803Y217684D03*
Y212684D03*
X902803Y217684D03*
Y212684D03*
X868376Y271313D03*
X873376D03*
X880122Y216781D03*
X875122D03*
X880222Y211781D03*
X875222D03*
X896030Y296330D03*
X901030D03*
X900995Y290712D03*
X895995D03*
X900819Y316367D03*
X895819D03*
X900716Y311058D03*
X895716D03*
X864207Y300314D03*
Y309914D03*
Y305114D03*
Y295314D03*
Y290314D03*
Y285314D03*
X888548Y392923D03*
X883548D03*
X893548D03*
X888548Y387923D03*
X893548D03*
X883548D03*
G54D36*
X666929Y510236D03*
X765354D03*
G54D39*
X801024Y24409D03*
X811024D03*
X821024D03*
G54D23*
X168898Y548819D03*
X184645Y539370D03*
X194094D03*
X203542Y545671D03*
X197243Y539371D03*
X194093Y564569D03*
X190944D03*
X194093Y555120D03*
X184646D03*
X153149Y536221D03*
X165748Y558268D03*
X172048Y555120D03*
X156297Y558267D03*
X187925Y564617D03*
X168898Y561417D03*
X206692Y555120D03*
X165745Y564567D03*
X168895D03*
X159449Y561417D03*
X165748D03*
X172047D03*
X162598Y558268D03*
X168898D03*
X165748Y555118D03*
X159449D03*
X162599Y551970D03*
X194093D03*
X197243D03*
X190945Y545669D03*
X172047D03*
Y551970D03*
X159449Y545671D03*
X162599Y545669D03*
X165749D03*
X212991Y561419D03*
X184646Y548821D03*
Y545671D03*
X184645Y542519D03*
X206693Y542520D03*
X159449Y542521D03*
X171906Y534661D03*
X212991Y542519D03*
X156299Y545671D03*
X165749Y548819D03*
X175197Y545671D03*
X162599Y542519D03*
X168898D03*
X156299Y542521D03*
X181496Y542520D03*
X159449Y548821D03*
X194094Y542519D03*
X172047Y548819D03*
X168898Y551969D03*
X162599Y548821D03*
X162598Y561417D03*
X168898Y555119D03*
X181497Y548821D03*
X178346Y545670D03*
X181497Y545671D03*
X162595Y564567D03*
X203542Y551970D03*
X181497Y555120D03*
X178346Y555119D03*
X187885Y552058D03*
X197245Y555118D03*
X159412Y552006D03*
X165748Y551968D03*
X178347Y564569D03*
X203543Y561418D03*
Y564568D03*
X200393Y548819D03*
X209842Y545669D03*
Y564567D03*
Y558268D03*
X212992Y551969D03*
Y548819D03*
X209842Y561417D03*
X212992Y564567D03*
X200393Y545669D03*
X206692Y545671D03*
X209842Y548819D03*
X212992Y545669D03*
X165777Y542555D03*
X209842Y555119D03*
Y551969D03*
X206692Y548820D03*
X206693Y551969D03*
X194094Y545669D03*
Y548820D03*
X175197Y548821D03*
X168898Y545669D03*
X153150Y539371D03*
X153149Y542521D03*
X197244Y545669D03*
Y542519D03*
X156300Y539371D03*
X197243Y589900D03*
X194094Y602362D03*
X206692Y596063D03*
X203450Y592912D03*
X194093Y596063D03*
X172020Y577050D03*
X175196Y589764D03*
X190944Y577166D03*
X194093Y574016D03*
Y567718D03*
X190944Y574016D03*
Y567718D03*
X187795Y577166D03*
X184646D03*
X172048Y589764D03*
X168898D03*
X187844Y574065D03*
X184645Y574166D03*
X187746Y567669D03*
X184695Y567666D03*
X184646Y570867D03*
X168898Y570866D03*
X156299Y586614D03*
Y580315D03*
X159449Y567717D03*
X156299Y570866D03*
X200393Y589764D03*
X187900Y589800D03*
X187794Y586614D03*
X203542Y589764D03*
X200393Y596063D03*
X187795Y592914D03*
X203605Y605821D03*
X187795Y602363D03*
X153149Y605513D03*
X206692Y592913D03*
X165748Y583464D03*
X209842D03*
X212992Y586614D03*
X212991Y567718D03*
X209841Y574016D03*
X206692D03*
X168898Y567717D03*
X159449Y570866D03*
X168898Y583464D03*
Y577165D03*
X159449Y586614D03*
X162598Y580315D03*
Y586614D03*
X165748D03*
X168898D03*
X159449Y577165D03*
X156299D03*
X168898Y580315D03*
X159449D03*
X162598Y577165D03*
X165748Y580315D03*
X162598Y583464D03*
X165748Y570866D03*
Y567717D03*
X162598D03*
X172047Y570867D03*
X212992Y580315D03*
X212991Y577165D03*
X209842Y567717D03*
X212991Y574016D03*
X190945Y599213D03*
X190944Y596063D03*
X187796Y599212D03*
X181586Y599123D03*
X212991Y583465D03*
X209841Y577165D03*
X159448Y596063D03*
X190944Y602362D03*
X203543D03*
X203542Y596063D03*
X194094Y599213D03*
X168898Y596063D03*
X212992Y602363D03*
X212991Y599212D03*
X206692Y589763D03*
X168898Y592913D03*
X162598Y596063D03*
X194093Y589764D03*
Y592913D03*
X206692Y586614D03*
X209842Y586613D03*
X212992Y589764D03*
X209841Y592913D03*
X162598Y570866D03*
X178347Y574018D03*
X203542Y580315D03*
Y586614D03*
X190944D03*
X178346Y586615D03*
X181497Y586614D03*
X178344Y577166D03*
X203542Y577165D03*
X178347Y570769D03*
X203501Y571005D03*
X178346Y596064D03*
X178347Y599213D03*
X165748D03*
X168898D03*
X162598D03*
X159448D03*
X172048Y596063D03*
X190944Y592913D03*
Y589764D03*
X200393Y586614D03*
X197165Y586540D03*
X212993Y592912D03*
X209842Y589763D03*
X206692Y580315D03*
X209841D03*
X181500Y595900D03*
X200393Y592912D03*
X209841Y599212D03*
X200393D03*
X159448Y589764D03*
Y592913D03*
X162598Y589764D03*
X165748D03*
Y596063D03*
Y592913D03*
X175197D03*
X172048D03*
X181530Y592765D03*
X175197Y596063D03*
Y599213D03*
X172048D03*
X216141Y564569D03*
Y561419D03*
X219291Y542519D03*
X216141D03*
X216142Y548820D03*
X216141Y555120D03*
Y558269D03*
X222441Y548820D03*
X219291D03*
X216141Y551970D03*
X216142Y545669D03*
X216141Y580315D03*
X222440Y605512D03*
X216141Y577165D03*
Y583465D03*
Y567718D03*
X219293Y567717D03*
X216141Y574016D03*
Y599212D03*
Y589762D03*
X230600Y608100D03*
X355600Y172900D03*
X363400Y115950D03*
G54D38*
X745669Y510236D03*
X844094D03*
G54D26*
X346457Y57007D03*
X353543Y62913D03*
Y55039D03*
X346457Y66850D03*
Y74724D03*
Y84567D03*
X353543Y86535D03*
Y78661D03*
Y70787D03*
G54D29*
X305906Y182874D03*
G54D10*
X61024Y34449D03*
X33464D03*
X56102Y24606D03*
X38386D03*
X108268Y44292D03*
X80708D03*
X103346Y34449D03*
X85630D03*
G54D22*
X76549Y680547D03*
Y675547D03*
X81549Y680547D03*
Y675547D03*
X305882Y195474D03*
X305382Y190174D03*
X653601Y46761D03*
X658601D03*
X653601Y51761D03*
X658601D03*
X663601Y46761D03*
Y51761D03*
X668601Y46761D03*
Y51761D03*
X896031Y228468D03*
Y223468D03*
X891031D03*
Y228468D03*
Y238468D03*
X896031D03*
X891031Y233468D03*
X896031D03*
G54D40*
X845198Y552063D03*
X837066Y543931D03*
G54D11*
X66435Y8514D03*
X61435D03*
X56435D03*
X51435D03*
X46435D03*
X41435D03*
X36435D03*
X31435D03*
X26435D03*
X21435D03*
X16435D03*
X8514Y10593D03*
Y15593D03*
Y20593D03*
Y25593D03*
Y30593D03*
Y35593D03*
Y40593D03*
Y45593D03*
Y50593D03*
Y55593D03*
Y60593D03*
X43000Y59500D03*
X51000D03*
X34000Y59400D03*
X8514Y65593D03*
Y70593D03*
Y75593D03*
Y80593D03*
Y85593D03*
Y90593D03*
Y95593D03*
Y100593D03*
Y105593D03*
Y110593D03*
Y115593D03*
Y120593D03*
Y125593D03*
Y130593D03*
Y135593D03*
Y140593D03*
Y145593D03*
Y150593D03*
Y155593D03*
Y160593D03*
Y165593D03*
Y170593D03*
Y175593D03*
Y180593D03*
Y185593D03*
Y190593D03*
Y195593D03*
Y200593D03*
Y205593D03*
Y210593D03*
Y215593D03*
Y220593D03*
Y225593D03*
Y230593D03*
Y235593D03*
Y240593D03*
Y245593D03*
Y250593D03*
Y255593D03*
Y260593D03*
Y265593D03*
Y270593D03*
Y275593D03*
Y280593D03*
Y285593D03*
Y290593D03*
Y295593D03*
Y300593D03*
Y305593D03*
Y310593D03*
Y315593D03*
Y320593D03*
Y325593D03*
Y330593D03*
Y335593D03*
Y340593D03*
Y345593D03*
Y350593D03*
Y355593D03*
Y360593D03*
Y365593D03*
Y370593D03*
Y375593D03*
Y380593D03*
Y385593D03*
Y390593D03*
Y395593D03*
Y400593D03*
Y405593D03*
Y410593D03*
Y415593D03*
Y420593D03*
Y425593D03*
Y430593D03*
Y435593D03*
Y440593D03*
Y445593D03*
Y450593D03*
Y455593D03*
Y460593D03*
Y465593D03*
Y470593D03*
Y475593D03*
Y480593D03*
Y485593D03*
Y490593D03*
Y495593D03*
Y500593D03*
Y505593D03*
Y510593D03*
Y515593D03*
Y520593D03*
Y525593D03*
Y530593D03*
Y535593D03*
Y540593D03*
Y545593D03*
Y550593D03*
Y555593D03*
Y560593D03*
Y565593D03*
X64701Y561266D03*
X63456Y555041D03*
X64701Y542366D03*
X64151Y521695D03*
X53524Y521269D03*
Y526995D03*
Y532622D03*
X52613Y538242D03*
X52408Y543876D03*
X52603Y549526D03*
X52485Y555153D03*
X53300Y560879D03*
X8514Y570593D03*
Y575593D03*
Y580593D03*
Y585593D03*
Y590593D03*
Y595593D03*
Y600593D03*
Y605593D03*
Y610593D03*
Y615593D03*
Y620593D03*
Y625593D03*
Y630593D03*
Y635593D03*
X67853Y577015D03*
X64703Y586463D03*
X64701Y567566D03*
X8514Y640593D03*
Y645593D03*
Y650593D03*
Y655593D03*
Y660593D03*
Y665593D03*
Y670593D03*
Y675593D03*
Y680593D03*
Y685593D03*
Y690593D03*
Y695593D03*
Y700593D03*
Y705593D03*
Y710593D03*
X56100Y676000D03*
X8514Y715593D03*
Y720593D03*
X9942Y725256D03*
X12178Y729728D03*
X14414Y734200D03*
X16650Y738672D03*
X18886Y743144D03*
X21122Y747617D03*
X23358Y752089D03*
X111683Y63266D03*
Y58266D03*
Y23266D03*
Y18266D03*
Y13266D03*
X111435Y8514D03*
X106435D03*
X101435D03*
X96435D03*
X91435D03*
X86435D03*
X81435D03*
X76435D03*
X71435D03*
X111683Y118266D03*
Y113266D03*
Y108266D03*
Y103266D03*
Y98266D03*
Y93266D03*
Y88266D03*
Y83266D03*
Y78266D03*
Y73266D03*
Y68266D03*
X90768Y69755D03*
X82768D03*
X73768Y69655D03*
X111683Y203266D03*
Y198266D03*
Y193266D03*
Y188266D03*
Y183266D03*
Y178266D03*
Y173266D03*
Y168266D03*
Y163266D03*
Y158266D03*
Y153266D03*
Y148266D03*
Y278266D03*
Y273266D03*
Y268266D03*
Y263266D03*
Y258266D03*
Y253266D03*
Y248266D03*
Y243266D03*
Y238266D03*
Y233266D03*
Y228266D03*
Y223266D03*
Y218266D03*
Y213266D03*
Y208266D03*
Y348266D03*
Y343266D03*
Y338266D03*
Y333266D03*
Y328266D03*
Y323266D03*
Y318266D03*
Y313266D03*
Y308266D03*
Y303266D03*
Y298266D03*
Y293266D03*
Y288266D03*
Y283266D03*
Y418266D03*
Y413266D03*
Y408266D03*
Y403266D03*
Y398266D03*
Y393266D03*
Y388266D03*
Y383266D03*
Y378266D03*
Y373266D03*
Y368266D03*
Y363266D03*
Y358266D03*
Y353266D03*
X108500Y475500D03*
X97074Y492891D03*
X112722Y493971D03*
X98400Y473200D03*
X123300Y530300D03*
X119400Y521700D03*
X94720Y557158D03*
X92286Y521695D03*
X86659D03*
X81032D03*
X75405D03*
X69778D03*
X97913D03*
X118900Y609900D03*
X116400Y626600D03*
X76118Y625275D03*
X81118D03*
X94011Y597066D03*
X101608Y596523D03*
X93048Y580164D03*
X93049Y573864D03*
X93051Y587466D03*
X83600Y567565D03*
X94106Y699683D03*
X76395Y755266D03*
X81395D03*
X86395D03*
X91395D03*
X96395D03*
X101395D03*
X106395D03*
X93928Y744775D03*
X83125Y719240D03*
Y724040D03*
X143700Y469000D03*
X167821Y488301D03*
X208370Y491570D03*
X200260Y465900D03*
X211324Y489886D03*
X187500Y523700D03*
X154730Y512704D03*
X158241Y512675D03*
X170700Y513600D03*
X182870Y513832D03*
X212300Y529000D03*
X141980Y508590D03*
X146900Y512500D03*
X185100Y614300D03*
X179700Y615300D03*
X151800Y615400D03*
X205827Y695000D03*
X188600Y696800D03*
X159058Y641132D03*
X142572Y640332D03*
X150872D03*
X177100Y640400D03*
X173000D03*
X193400Y639700D03*
X189500D03*
X185300D03*
X181000D03*
X198700D03*
X275700Y490300D03*
X275100Y472400D03*
X264800Y467400D03*
X278800Y467500D03*
X272100Y537500D03*
X251346Y554100D03*
X256816Y563982D03*
X262996Y548757D03*
X231450Y563000D03*
X270021Y549394D03*
X283600Y539294D03*
X242700Y548600D03*
X252400Y539600D03*
X271715Y556690D03*
X263400Y531500D03*
X231200Y576800D03*
X234700Y581600D03*
X254408Y586483D03*
X255400Y579500D03*
X225900Y630988D03*
X230063Y618667D03*
X274100Y591000D03*
X279745Y608000D03*
X255663Y617763D03*
X276376Y574132D03*
X281636Y588796D03*
X231000Y571900D03*
X231500Y659100D03*
X255050Y675750D03*
X271240Y698960D03*
X243731Y709100D03*
X272900Y669100D03*
X254600Y685100D03*
X278150Y648363D03*
X284000Y678300D03*
X263800Y648902D03*
X236000Y646100D03*
X254648Y745463D03*
X268520Y719420D03*
X249200Y733700D03*
Y728700D03*
Y723700D03*
Y718700D03*
Y738500D03*
X258431Y712169D03*
X330546Y8514D03*
X325546D03*
X320546D03*
X315546D03*
X310546D03*
X305546D03*
X300546D03*
X296034Y9002D03*
X335061Y222578D03*
X335100Y218378D03*
Y228117D03*
X336000Y384400D03*
X302700Y551300D03*
X339062Y521100D03*
X344600Y507600D03*
X341300Y536200D03*
X352921Y536521D03*
X311900Y514900D03*
X287500Y518000D03*
X297850Y524500D03*
X353500Y624500D03*
X353669Y600881D03*
X302300Y582000D03*
X286700Y611911D03*
X340920Y575234D03*
X348000Y612661D03*
X352472Y581000D03*
X325762Y596900D03*
X291839Y578193D03*
X293697Y589566D03*
X289070Y573080D03*
X322000Y653081D03*
X312400D03*
X317200D03*
X307600D03*
X328356Y678679D03*
X297900Y664800D03*
X326395Y755266D03*
X331395D03*
X336395D03*
X291700Y737000D03*
X305559Y720973D03*
X310559D03*
X305559Y725973D03*
X310559D03*
X299500Y725400D03*
X316465Y716063D03*
X428740Y179528D03*
X373073Y201889D03*
X365800Y193750D03*
X363828Y243944D03*
X361250Y491650D03*
X372714Y509275D03*
X364000Y525500D03*
X387400Y547500D03*
X367133Y596067D03*
X382380Y612620D03*
X371180Y629236D03*
X386224Y580524D03*
X383411Y577024D03*
X362250Y570875D03*
X399754Y706071D03*
X386050Y701200D03*
X389168Y743572D03*
X391404Y739100D03*
X393640Y734628D03*
X395876Y730156D03*
X398112Y725684D03*
X399754Y716071D03*
Y711071D03*
X379450Y714400D03*
X491500Y71600D03*
X496500D03*
X491500Y76600D03*
X496500D03*
X457086Y179528D03*
X442913D03*
X471260D03*
X516693Y41545D03*
X521493D03*
Y36745D03*
X516693D03*
X521493Y31945D03*
X516693D03*
X513500Y62000D03*
X538456Y65144D03*
X506500Y76600D03*
X501500D03*
Y71600D03*
X542126Y179528D03*
X556299D03*
X626647Y77507D03*
Y72507D03*
X576624Y193205D03*
Y198205D03*
Y203205D03*
Y208205D03*
Y213205D03*
Y223205D03*
Y228205D03*
Y233205D03*
Y238205D03*
Y243205D03*
Y248205D03*
Y253205D03*
Y258205D03*
Y263205D03*
Y268205D03*
Y273205D03*
Y278205D03*
Y333205D03*
Y338205D03*
Y343205D03*
Y348205D03*
Y353205D03*
Y358205D03*
Y363205D03*
Y368205D03*
Y373205D03*
Y378205D03*
Y383205D03*
Y388205D03*
Y393205D03*
Y398205D03*
Y403205D03*
Y408205D03*
Y413205D03*
Y418205D03*
Y423205D03*
Y428205D03*
Y433205D03*
Y438205D03*
Y443205D03*
Y448205D03*
Y498205D03*
Y503205D03*
Y508205D03*
Y513205D03*
Y518205D03*
Y523205D03*
Y528205D03*
Y533205D03*
Y538205D03*
Y543205D03*
Y548205D03*
Y553205D03*
Y558205D03*
Y563205D03*
Y568205D03*
Y573205D03*
Y578205D03*
Y583205D03*
Y588205D03*
X578710Y592712D03*
X580946Y597184D03*
X583182Y601656D03*
X585418Y606129D03*
X587654Y610601D03*
X635975Y621407D03*
X640975D03*
X715546Y8514D03*
X710546D03*
X705546D03*
X700546D03*
X695546D03*
X710550Y18550D03*
X700065Y135985D03*
Y125985D03*
Y115985D03*
X710065D03*
Y125985D03*
Y135985D03*
X700065Y155985D03*
X710065D03*
Y145985D03*
X696159Y225829D03*
X698909Y278104D03*
X700065Y265985D03*
Y255985D03*
Y245985D03*
Y235985D03*
X710065D03*
Y245985D03*
Y255985D03*
Y265985D03*
X709625Y275991D03*
X710065Y325985D03*
Y315985D03*
X711574Y285985D03*
X708307Y295429D03*
X710065Y305985D03*
Y335985D03*
Y345985D03*
X700065Y385985D03*
Y395985D03*
Y405985D03*
Y415985D03*
X710065Y375985D03*
Y355985D03*
Y365985D03*
Y455985D03*
X684399Y466984D03*
Y471984D03*
X706275Y445986D03*
X663500Y484000D03*
Y489000D03*
Y494000D03*
X692282Y476720D03*
X700900Y423800D03*
X693392Y520482D03*
X683392D03*
X688392D03*
X705080Y521247D03*
X694272Y495786D03*
X713189Y524511D03*
X707283D03*
X701378D03*
X695472D03*
X689567D03*
X683661D03*
X677756D03*
X662400Y519500D03*
X666800D03*
X657199Y530195D03*
X671850Y524511D03*
X645975Y621407D03*
X650975D03*
X655975D03*
X660975D03*
X665975D03*
X670975D03*
X675975D03*
X680975D03*
X685975D03*
X690975D03*
X695975D03*
X700975D03*
X705975D03*
X710975D03*
X715975D03*
X785546Y8514D03*
X780546D03*
X775546D03*
X770546D03*
X765546D03*
X760546D03*
X755546D03*
X750546D03*
X745546D03*
X740546D03*
X735546D03*
X730546D03*
X725546D03*
X720546D03*
X770065Y65985D03*
Y75985D03*
X750065Y85985D03*
X770065D03*
X760065D03*
X740065D03*
X730065Y95985D03*
X760065D03*
X780065D03*
X770065D03*
Y105985D03*
X780065D03*
Y115985D03*
X730065Y135985D03*
Y125985D03*
Y115985D03*
Y105985D03*
X750065Y95985D03*
X740065D03*
X750065Y105985D03*
X760065D03*
X740065D03*
X750065Y115985D03*
X760065D03*
X770065D03*
X740065D03*
X750065Y125985D03*
X760065D03*
X770065D03*
X780065D03*
X740065D03*
X750065Y135985D03*
X760065D03*
X770065D03*
X780065D03*
X740065D03*
X720065Y105985D03*
Y115985D03*
Y125985D03*
Y135985D03*
Y155985D03*
X780065D03*
X730065D03*
Y145985D03*
X750065D03*
X760065D03*
X770065D03*
X780065D03*
X740065D03*
X750065Y155985D03*
X760065D03*
X770065D03*
X740065D03*
X750065Y165985D03*
X760065D03*
X770065D03*
X740065D03*
X750065Y175985D03*
X760065D03*
X770065D03*
X740065D03*
X750065Y185985D03*
X760065D03*
X770065D03*
X740065D03*
X750065Y195985D03*
X760065D03*
X770065D03*
X740065D03*
X750065Y205985D03*
X760065D03*
X770065D03*
X740065D03*
X720065Y145985D03*
X730065Y215985D03*
X773469Y277001D03*
X780065Y275985D03*
X787817Y275879D03*
X750065Y215985D03*
X760065D03*
X770065D03*
X780065D03*
X740065D03*
X780065Y265985D03*
Y255985D03*
Y245985D03*
Y235985D03*
Y225985D03*
X770065Y265985D03*
Y255985D03*
Y245985D03*
Y235985D03*
Y225985D03*
X763133Y275881D03*
X759790Y263326D03*
X760065Y255985D03*
Y245985D03*
Y235985D03*
Y225985D03*
X750065Y275985D03*
Y265985D03*
Y255985D03*
Y245985D03*
Y235985D03*
Y225985D03*
X741608Y277171D03*
X740065Y265985D03*
Y255985D03*
Y245985D03*
Y235985D03*
Y225985D03*
X730830Y276087D03*
X730065Y265985D03*
Y255985D03*
X731766Y246017D03*
X730065Y235985D03*
X730190Y223549D03*
X720237Y223228D03*
X720065Y235985D03*
X721766Y246017D03*
X720065Y255985D03*
Y265985D03*
X718617Y275736D03*
X770065Y335985D03*
X760065D03*
X720065Y325985D03*
X760065D03*
X750065D03*
X740065D03*
X730065D03*
X720065Y315985D03*
X780065Y285985D03*
X770065D03*
X760065D03*
X750065Y295985D03*
X760065D03*
X770065D03*
X780065D03*
Y305985D03*
Y315985D03*
Y325985D03*
Y335985D03*
Y345985D03*
X770065Y305985D03*
Y315985D03*
Y325985D03*
Y345985D03*
X760065Y305985D03*
Y315985D03*
Y345985D03*
X750065Y305985D03*
Y315985D03*
Y335985D03*
Y345985D03*
X740065Y305985D03*
Y315985D03*
Y335985D03*
Y345985D03*
X730065D03*
Y335985D03*
Y315985D03*
X752500Y286000D03*
X740065Y295985D03*
X741000Y286000D03*
X730065Y305985D03*
X729486Y296094D03*
X729294Y285987D03*
X721574Y285985D03*
X719049Y296011D03*
X720065Y305985D03*
Y335985D03*
Y345985D03*
X750065Y415985D03*
X760065D03*
X770065D03*
X780065D03*
X730065D03*
X740065D03*
X750065Y405985D03*
X760065D03*
X770065D03*
X780065D03*
X730065D03*
X740065D03*
X780065Y395985D03*
X770065D03*
X760065D03*
X750065D03*
X740065D03*
X730065D03*
X720065Y375985D03*
X730065Y365985D03*
Y375985D03*
Y385985D03*
X750065D03*
X760065D03*
X770065D03*
X780065D03*
X740065D03*
X750065Y375985D03*
X760065D03*
X770065D03*
X780065D03*
X740065D03*
X750065Y365985D03*
X760065D03*
X770065D03*
X780065D03*
X740065D03*
X780065Y355985D03*
X770065D03*
X760065D03*
X750065D03*
X740065D03*
X730065D03*
X720065D03*
Y365985D03*
X783800Y422800D03*
X720065Y455985D03*
Y465985D03*
X750065D03*
X760065D03*
X770065D03*
X780065D03*
X730065D03*
X740065D03*
X780065Y455985D03*
X770065D03*
X760065D03*
X750065D03*
X740065D03*
X730065D03*
X750065Y445985D03*
X760065D03*
X770065D03*
X780065D03*
X730065D03*
X740065D03*
X750065Y435985D03*
X760065D03*
X770065D03*
X780065D03*
X740065D03*
X750065Y425985D03*
X760065D03*
X770065D03*
X780065D03*
X784604Y519082D03*
X758512Y534430D03*
X747107Y536580D03*
X739334Y524156D03*
X762679Y535537D03*
X742716Y536435D03*
X738779D03*
X782086D03*
X776181D03*
X770275D03*
X725000D03*
X719394Y536305D03*
X720975Y621407D03*
X725975D03*
X730975D03*
X735975D03*
X740975D03*
X745975D03*
X750975D03*
X755975D03*
X760975D03*
X765975D03*
X770975D03*
X775975D03*
X780975D03*
X785975D03*
X850546Y8514D03*
X845546D03*
X840546D03*
X835546D03*
X830546D03*
X825546D03*
X820546D03*
X815546D03*
X810546D03*
X805546D03*
X800546D03*
X795546D03*
X790546D03*
X820065Y105985D03*
Y135985D03*
Y125985D03*
Y115985D03*
X810065Y135985D03*
Y125985D03*
Y115985D03*
X790065Y105985D03*
X800065Y115985D03*
X790065D03*
Y125985D03*
X800065D03*
Y135985D03*
X790065D03*
X820065Y155985D03*
X810065D03*
X800065D03*
X790065D03*
X820065Y145985D03*
X810065D03*
X790065D03*
X800065D03*
X820313Y276188D03*
X810065Y275985D03*
X800065D03*
X820065Y265985D03*
Y255985D03*
Y245985D03*
Y235985D03*
Y225985D03*
X810065Y265985D03*
Y255985D03*
Y245985D03*
Y235985D03*
X800065Y265985D03*
Y255985D03*
Y245985D03*
Y235985D03*
X790065Y265985D03*
Y255985D03*
Y245985D03*
Y235985D03*
Y225985D03*
X820065Y305985D03*
Y295985D03*
Y285985D03*
X810065Y295985D03*
Y285985D03*
X800065D03*
X790065D03*
Y295985D03*
X800065D03*
X810065Y305985D03*
X810000Y314000D03*
X810065Y325985D03*
X800065Y305985D03*
Y315985D03*
Y325985D03*
Y335985D03*
Y345985D03*
X790065Y305985D03*
Y315985D03*
Y325985D03*
X791500Y336000D03*
X790065Y345985D03*
Y415985D03*
Y405985D03*
Y395985D03*
Y375985D03*
X800065D03*
X790065Y365985D03*
X800065D03*
Y355985D03*
X790065D03*
X809702Y416359D03*
X815600Y386200D03*
X800065Y455985D03*
Y465985D03*
X790065D03*
Y455985D03*
Y445985D03*
Y435985D03*
X790191Y426486D03*
X805771Y518743D03*
X789604Y519082D03*
X794604D03*
X825000Y536200D03*
X817519Y536435D03*
X811614D03*
X805708D03*
X841141D03*
X837204D03*
X799803D03*
X793897D03*
X787992D03*
X790975Y621407D03*
X795975D03*
X800975D03*
X805975D03*
X810975D03*
X815975D03*
X820975D03*
X825975D03*
X830975D03*
X835975D03*
X840975D03*
X854971Y637313D03*
Y642313D03*
Y647313D03*
Y652313D03*
Y657313D03*
Y662313D03*
Y667313D03*
Y672313D03*
Y677313D03*
Y682313D03*
Y687313D03*
Y692313D03*
Y697313D03*
Y702313D03*
Y707313D03*
Y712313D03*
X916683Y62377D03*
Y57377D03*
Y52377D03*
Y47377D03*
Y42377D03*
Y37377D03*
Y32377D03*
Y27377D03*
Y22377D03*
Y17377D03*
X915546Y8514D03*
X910546D03*
X905546D03*
X900546D03*
X916683Y132377D03*
Y127377D03*
Y122377D03*
Y117377D03*
Y112377D03*
Y107377D03*
Y102377D03*
Y97377D03*
Y92377D03*
Y87377D03*
Y82377D03*
Y77377D03*
Y72377D03*
Y67377D03*
Y207377D03*
Y202377D03*
Y197377D03*
Y192377D03*
Y187377D03*
Y182377D03*
Y177377D03*
Y172377D03*
Y167377D03*
Y162377D03*
Y157377D03*
Y152377D03*
Y147377D03*
Y142377D03*
Y137377D03*
Y277377D03*
Y272377D03*
Y267377D03*
Y262377D03*
Y257377D03*
Y252377D03*
Y247377D03*
Y242377D03*
Y237377D03*
Y232377D03*
Y227377D03*
Y222377D03*
Y217377D03*
Y212377D03*
Y347377D03*
Y342377D03*
Y337377D03*
Y332377D03*
Y327377D03*
Y322377D03*
Y317377D03*
Y312377D03*
Y307377D03*
Y302377D03*
Y297377D03*
Y292377D03*
Y287377D03*
Y282377D03*
Y422377D03*
Y417377D03*
Y412377D03*
Y407377D03*
Y402377D03*
Y397377D03*
Y392377D03*
Y387377D03*
Y382377D03*
Y377377D03*
Y372377D03*
Y367377D03*
Y362377D03*
Y357377D03*
Y352377D03*
X902091Y369397D03*
X897091D03*
X902091Y374397D03*
X897091D03*
Y379397D03*
X902091D03*
X916683Y492377D03*
Y487377D03*
Y482377D03*
Y477377D03*
Y472377D03*
Y467377D03*
Y462377D03*
Y457377D03*
Y452377D03*
Y447377D03*
Y442377D03*
Y437377D03*
Y432377D03*
Y427377D03*
Y562377D03*
Y557377D03*
Y552377D03*
Y547377D03*
Y542377D03*
Y537377D03*
Y532377D03*
Y527377D03*
Y522377D03*
Y517377D03*
Y512377D03*
Y507377D03*
Y502377D03*
Y497377D03*
Y637377D03*
Y632377D03*
Y627377D03*
Y622377D03*
Y617377D03*
Y612377D03*
Y607377D03*
Y602377D03*
Y597377D03*
Y592377D03*
Y587377D03*
Y582377D03*
Y577377D03*
Y572377D03*
Y567377D03*
Y707377D03*
Y702377D03*
Y697377D03*
Y692377D03*
Y687377D03*
Y682377D03*
Y677377D03*
Y672377D03*
Y667377D03*
Y662377D03*
Y657377D03*
Y652377D03*
Y647377D03*
Y642377D03*
X901041Y753684D03*
X903277Y749212D03*
X905513Y744740D03*
X907749Y740268D03*
X909985Y735796D03*
X912221Y731323D03*
X914457Y726851D03*
X916683Y722377D03*
Y717377D03*
Y712377D03*
G54D35*
X706299Y83661D03*
Y201771D03*
X804724Y83661D03*
Y201772D03*
G54D33*
X488838Y164744D03*
G54D13*
X34652Y111485D03*
X33297Y703990D03*
X148206Y21054D03*
X261147Y405580D03*
X486498Y356293D03*
X807831Y734367D03*
X899219Y47960D03*
G54D32*
X488838Y137225D03*
G54D18*
X89764Y238386D03*
X309252Y413583D03*
G54D25*
X163189Y669291D03*
G54D28*
X339331Y91929D03*
X360669Y49803D03*
G54D19*
X90157Y413582D03*
X309055Y157677D03*
G54D14*
X70865Y98425D03*
Y472441D03*
X314960D03*
X364173Y740157D03*
X405511Y39370D03*
X587795Y307087D03*
X590551Y472441D03*
X612204Y606299D03*
X875984Y472441D03*
Y606299D03*
Y740157D03*
G54D17*
X49212D03*
X875984Y31496D03*
G54D15*
X67853Y561266D03*
Y570715D03*
X92600Y535623D03*
X86750Y561265D03*
X89899D03*
Y567565D03*
X181497Y551970D03*
X175197D03*
X178347D03*
X203542Y555120D03*
X187795D03*
X200393Y551970D03*
X206692Y558269D03*
Y561419D03*
Y564569D03*
X175196Y558269D03*
X172047Y564568D03*
X194094Y577166D03*
X203543Y574017D03*
X178347Y589764D03*
X181497D03*
X194093Y586614D03*
X209841Y596063D03*
X206692Y583465D03*
Y567600D03*
X175298Y577266D03*
X172047Y567717D03*
X216141Y586614D03*
X716100Y442100D03*
X721100D03*
X820059Y331701D03*
X815541Y354089D03*
X804000Y441100D03*
X799000D03*
X883222Y59214D03*
X888022D03*
X892822D03*
X897622D03*
X880922Y63714D03*
X885722D03*
X890522D03*
X895322D03*
X900122D03*
G54D21*
X74152Y583312D03*
X188708Y468154D03*
X175115Y463761D03*
X167656Y465300D03*
X189700Y463500D03*
X185615Y498015D03*
X174900Y499800D03*
X336230Y377800D03*
X324900Y581600D03*
X421653Y126378D03*
X428740Y121654D03*
Y135827D03*
X421653Y183071D03*
Y140551D03*
Y154725D03*
X428740Y150000D03*
X421653Y168898D03*
X428740Y164173D03*
X435827Y126378D03*
X450000D03*
X464173D03*
X442913Y121654D03*
X457086D03*
X471260D03*
X442913Y135827D03*
X457086D03*
X471260D03*
X435827Y183071D03*
X450000D03*
X464173D03*
X435827Y140551D03*
X450000D03*
X464173D03*
X435827Y154725D03*
X442913Y150000D03*
X450000Y154725D03*
X457086Y150000D03*
X464173Y154725D03*
X471260Y150000D03*
X435827Y168898D03*
X442913Y164173D03*
X450000Y168898D03*
X457086Y164173D03*
X464173Y168898D03*
X471260Y164173D03*
X535039Y126378D03*
X549212D03*
X542126Y121654D03*
X556299D03*
X542126Y135827D03*
X556299D03*
X535039Y183071D03*
X549212D03*
X535039Y140551D03*
X549212D03*
X535039Y154725D03*
X542126Y150000D03*
X549212Y154725D03*
X556299Y150000D03*
X506693Y159055D03*
Y164567D03*
X535039Y168898D03*
X542126Y164173D03*
X549212Y168898D03*
X556299Y164173D03*
X506693Y173229D03*
Y178740D03*
X513779Y174016D03*
X725288Y405950D03*
X740500Y426800D03*
X716536Y523519D03*
X728036D03*
X842511Y164078D03*
X808188Y404950D03*
X856720Y409372D03*
X822300Y418900D03*
X876451Y407949D03*
X880665Y410841D03*
X885665D03*
X890665D03*
X895665D03*
X900665D03*
G54D37*
X715000Y547027D03*
X705853Y549017D03*
X713985Y557149D03*
X696624Y548249D03*
X704756Y556381D03*
X683369Y549269D03*
X691501Y557401D03*
X681989Y540183D03*
X690121Y548315D03*
X668195Y541742D03*
X676327Y549874D03*
X655092Y536171D03*
X663224Y544303D03*
X785434Y551934D03*
X775934Y550934D03*
X784066Y559066D03*
X765434Y549934D03*
X773566Y558066D03*
X753434Y545434D03*
X761566Y553566D03*
X725853Y547117D03*
X733985Y555249D03*
X723132Y555159D03*
X822434Y550434D03*
X830566Y558566D03*
X809934Y545434D03*
X818066Y553566D03*
X803934Y551934D03*
X812066Y560066D03*
X794934Y551434D03*
X803066Y559566D03*
X793566Y560066D03*
%LPC*%
G75*
G54D41*
G01X-36569Y-23804D02*
Y-103804D01*
G01D02*
X1258031D01*
G01X-40569Y-7804D02*
G02I-12000J0D01*
G01X-45719D02*
G02I-6850J0D01*
G01X-52569Y-23804D02*
Y8196D01*
G01X-36569Y-23804D02*
X1258031D01*
G01X-36569Y-59304D02*
X1258031D01*
G01X-36569Y-7804D02*
X-68569D01*
G01X470531Y-23804D02*
Y-103804D01*
G01X608031Y-23804D02*
Y-103804D01*
G01X723031Y-23804D02*
Y-103804D01*
G01X890531Y-23804D02*
Y-103804D01*
G01X1060531Y-23804D02*
Y-103804D01*
G01X1258031Y-23804D02*
Y-103804D01*
G01X1286031Y-7804D02*
G02I-12000J0D01*
G01X1280881D02*
G02I-6850J0D01*
G01X1274031Y-23804D02*
Y8196D01*
G01X1290031Y-7804D02*
X1258031D01*
G54D42*
G01X-9023Y-84471D02*
X-8149Y-83596D01*
X-7494Y-82138D01*
X-7057Y-80095D01*
X-7494Y-78346D01*
X-8367Y-77179D01*
X-9896Y-76304D01*
X-15791D01*
Y-93804D01*
X-8586D01*
X-7057Y-92638D01*
X-6184Y-90887D01*
X-5747Y-88846D01*
X-6184Y-86804D01*
X-7494Y-85054D01*
X-9023Y-84471D01*
X-15791D01*
G01X3674Y-93804D02*
Y-82138D01*
G01Y-84471D02*
X4766Y-83304D01*
X5858Y-82429D01*
X7386Y-82138D01*
X8477Y-82429D01*
X9788Y-83304D01*
G01X19646Y-99054D02*
X20956Y-99637D01*
X22703Y-99054D01*
X23794Y-97888D01*
X24668Y-96429D01*
X25977Y-91763D01*
X28816Y-82138D01*
G01X21829D02*
X25977Y-91763D01*
G01X45224Y-83596D02*
X43696Y-82429D01*
X42386Y-82138D01*
X40639Y-82721D01*
X39329Y-83887D01*
X38456Y-85929D01*
X38237Y-87971D01*
X38456Y-90013D01*
X39329Y-91763D01*
X40639Y-93221D01*
X42386Y-93804D01*
X43914Y-93221D01*
X45224Y-92054D01*
G01X55956Y-85929D02*
X62943D01*
X62288Y-83887D01*
X61196Y-82721D01*
X59668Y-82138D01*
X58139Y-82429D01*
X56829Y-83304D01*
X55956Y-85346D01*
X55519Y-87096D01*
Y-88846D01*
X55956Y-90596D01*
X57048Y-92346D01*
X58358Y-93512D01*
X59886Y-93804D01*
X61414Y-93221D01*
X62943Y-91471D01*
G01X99034Y-77763D02*
X97724Y-76887D01*
X96196Y-76304D01*
X94449D01*
X92484Y-77179D01*
X90956Y-78637D01*
X89864Y-80388D01*
X88991Y-83304D01*
X88772Y-85929D01*
X89209Y-88554D01*
X89864Y-90304D01*
X91174Y-92054D01*
X92703Y-93221D01*
X94231Y-93804D01*
X95759D01*
X97288Y-93221D01*
X98598Y-92346D01*
X99690Y-91180D01*
G01X115661Y-93804D02*
Y-82138D01*
G01Y-84179D02*
X114788Y-83013D01*
X113477Y-82429D01*
X111949Y-82138D01*
X110421Y-82721D01*
X109111Y-83887D01*
X108237Y-85637D01*
X107801Y-87971D01*
X108237Y-90304D01*
X109111Y-92054D01*
X110421Y-93221D01*
X111949Y-93804D01*
X113477Y-93512D01*
X114788Y-92638D01*
X115661Y-91471D01*
G01X125519Y-93804D02*
Y-82138D01*
G01Y-85054D02*
X126393Y-83596D01*
X127703Y-82429D01*
X129449Y-82138D01*
X130977Y-82429D01*
X132288Y-83596D01*
X132943Y-85637D01*
Y-93804D01*
G01X142146Y-99054D02*
X143456Y-99637D01*
X145203Y-99054D01*
X146294Y-97888D01*
X147168Y-96429D01*
X148477Y-91763D01*
X151316Y-82138D01*
G01X144329D02*
X148477Y-91763D01*
G01X164231Y-93804D02*
X162921Y-93512D01*
X161611Y-92346D01*
X160737Y-90304D01*
X160301Y-87971D01*
X160737Y-85637D01*
X161611Y-83596D01*
X162921Y-82429D01*
X164231Y-82138D01*
X165541Y-82429D01*
X166851Y-83596D01*
X167724Y-85637D01*
X167943Y-87971D01*
X167724Y-90304D01*
X166851Y-92346D01*
X165541Y-93512D01*
X164231Y-93804D01*
G01X178019D02*
Y-82138D01*
G01Y-85054D02*
X178893Y-83596D01*
X180203Y-82429D01*
X181949Y-82138D01*
X183477Y-82429D01*
X184788Y-83596D01*
X185443Y-85637D01*
Y-93804D01*
G01X214111Y-76304D02*
X219351D01*
G01X216731D02*
Y-93804D01*
G01X214111D02*
X219351D01*
G01X234231D02*
X232484Y-93512D01*
X230956Y-92346D01*
X229646Y-90596D01*
X228772Y-88554D01*
X228336Y-86221D01*
Y-83887D01*
X228772Y-81554D01*
X229646Y-79512D01*
X230956Y-77763D01*
X232484Y-76596D01*
X234231Y-76304D01*
X235977Y-76596D01*
X237506Y-77763D01*
X238816Y-79512D01*
X239690Y-81554D01*
X240126Y-83887D01*
Y-86221D01*
X239690Y-88554D01*
X238816Y-90596D01*
X237506Y-92346D01*
X235977Y-93512D01*
X234231Y-93804D01*
G01X246054D02*
Y-76304D01*
X251731Y-90887D01*
X257408Y-76304D01*
Y-93804D01*
G01X285639Y-99637D02*
X283456Y-96721D01*
X282364Y-93804D01*
Y-82138D01*
X283456Y-79221D01*
X285639Y-76304D01*
G01X298554Y-93804D02*
Y-76304D01*
X304231Y-90887D01*
X309908Y-76304D01*
Y-93804D01*
G01X321731Y-94387D02*
X321294Y-94096D01*
Y-93512D01*
X321731Y-93221D01*
X322168Y-93512D01*
Y-94096D01*
X321731Y-94387D01*
G01X335083Y-79221D02*
X336393Y-77471D01*
X337921Y-76596D01*
X339668Y-76304D01*
X341851Y-76887D01*
X343379Y-78346D01*
X343816Y-80095D01*
X343598Y-81846D01*
X342724Y-83304D01*
X338358Y-86221D01*
X336393Y-88262D01*
X335083Y-91180D01*
X334646Y-93804D01*
X343816D01*
G01X374231D02*
X372921Y-93512D01*
X371611Y-92346D01*
X370737Y-90304D01*
X370301Y-87971D01*
X370737Y-85637D01*
X371611Y-83596D01*
X372921Y-82429D01*
X374231Y-82138D01*
X375541Y-82429D01*
X376851Y-83596D01*
X377724Y-85637D01*
X377943Y-87971D01*
X377724Y-90304D01*
X376851Y-92346D01*
X375541Y-93512D01*
X374231Y-93804D01*
G01X388019D02*
Y-82138D01*
G01Y-85054D02*
X388893Y-83596D01*
X390203Y-82429D01*
X391949Y-82138D01*
X393477Y-82429D01*
X394788Y-83596D01*
X395443Y-85637D01*
Y-93804D01*
G01X409231D02*
Y-76304D01*
G01X422146Y-99054D02*
X423456Y-99637D01*
X425203Y-99054D01*
X426294Y-97888D01*
X427168Y-96429D01*
X428477Y-91763D01*
X431316Y-82138D01*
G01X424329D02*
X428477Y-91763D01*
G01X445323Y-99637D02*
X447506Y-96721D01*
X448598Y-93804D01*
Y-82138D01*
X447506Y-79221D01*
X445323Y-76304D01*
G01X176054Y-48804D02*
Y-31304D01*
X181731Y-45887D01*
X187408Y-31304D01*
Y-48804D01*
G01X199231D02*
X197921Y-48512D01*
X196611Y-47346D01*
X195737Y-45304D01*
X195301Y-42971D01*
X195737Y-40637D01*
X196611Y-38596D01*
X197921Y-37429D01*
X199231Y-37138D01*
X200541Y-37429D01*
X201851Y-38596D01*
X202724Y-40637D01*
X202943Y-42971D01*
X202724Y-45304D01*
X201851Y-47346D01*
X200541Y-48512D01*
X199231Y-48804D01*
G01X220661Y-31304D02*
Y-48804D01*
G01Y-46180D02*
X219788Y-47638D01*
X218477Y-48512D01*
X216949Y-48804D01*
X215203Y-48221D01*
X213893Y-46763D01*
X213019Y-45013D01*
X212801Y-42971D01*
X213019Y-40929D01*
X213893Y-39179D01*
X215203Y-37721D01*
X216949Y-37138D01*
X218477Y-37429D01*
X219569Y-38013D01*
X220661Y-39179D01*
G01X230956Y-40929D02*
X237943D01*
X237288Y-38887D01*
X236196Y-37721D01*
X234668Y-37138D01*
X233139Y-37429D01*
X231829Y-38304D01*
X230956Y-40346D01*
X230519Y-42096D01*
Y-43846D01*
X230956Y-45596D01*
X232048Y-47346D01*
X233358Y-48512D01*
X234886Y-48804D01*
X236414Y-48221D01*
X237943Y-46471D01*
G01X251731Y-48804D02*
Y-31304D01*
G01X504231Y-93804D02*
Y-76304D01*
X501611Y-79804D01*
G01Y-93804D02*
X506851D01*
G01X517583Y-86513D02*
X519111Y-84471D01*
X520421Y-83304D01*
X522168Y-82721D01*
X523696Y-83304D01*
X524788Y-84471D01*
X525661Y-86221D01*
X525879Y-88262D01*
X525661Y-90013D01*
X524788Y-91763D01*
X523477Y-93221D01*
X521949Y-93804D01*
X520203Y-93221D01*
X518674Y-91471D01*
X517801Y-88846D01*
X517583Y-85929D01*
X518019Y-82138D01*
X518674Y-80095D01*
X519766Y-78054D01*
X521294Y-76596D01*
X522823Y-76304D01*
X524351Y-76887D01*
X525443Y-78346D01*
G01X534428Y-90304D02*
X535737Y-92346D01*
X537484Y-93512D01*
X539449Y-93804D01*
X541196Y-93512D01*
X542943Y-92054D01*
X544034Y-90304D01*
X544253Y-88554D01*
X543816Y-86513D01*
X542288Y-85054D01*
X540759Y-84471D01*
X538794D01*
G01X540759D02*
X542069Y-83596D01*
X543161Y-82138D01*
X543598Y-80388D01*
X543161Y-78637D01*
X542069Y-77179D01*
X540104Y-76304D01*
X538139Y-76596D01*
X536174Y-77763D01*
G01X559351Y-93804D02*
Y-76304D01*
X551272Y-88846D01*
X562190D01*
G01X570083Y-79221D02*
X571393Y-77471D01*
X572921Y-76596D01*
X574668Y-76304D01*
X576851Y-76887D01*
X578379Y-78346D01*
X578816Y-80095D01*
X578598Y-81846D01*
X577724Y-83304D01*
X573358Y-86221D01*
X571393Y-88262D01*
X570083Y-91180D01*
X569646Y-93804D01*
X578816D01*
G01X491114Y-48804D02*
Y-31304D01*
X496354D01*
X498101Y-32179D01*
X499411Y-34221D01*
X499848Y-36554D01*
X499411Y-38887D01*
X498319Y-40637D01*
X496354Y-41513D01*
X491114D01*
G01X517784Y-32763D02*
X516474Y-31887D01*
X514946Y-31304D01*
X513199D01*
X511234Y-32179D01*
X509706Y-33637D01*
X508614Y-35388D01*
X507741Y-38304D01*
X507522Y-40929D01*
X507959Y-43554D01*
X508614Y-45304D01*
X509924Y-47054D01*
X511453Y-48221D01*
X512981Y-48804D01*
X514509D01*
X516038Y-48221D01*
X517348Y-47346D01*
X518440Y-46180D01*
G01X532227Y-39471D02*
X533101Y-38596D01*
X533756Y-37138D01*
X534193Y-35095D01*
X533756Y-33346D01*
X532883Y-32179D01*
X531354Y-31304D01*
X525459D01*
Y-48804D01*
X532664D01*
X534193Y-47638D01*
X535066Y-45887D01*
X535503Y-43846D01*
X535066Y-41804D01*
X533756Y-40054D01*
X532227Y-39471D01*
X525459D01*
G01X541431Y-54637D02*
X554531D01*
G01X560459Y-48804D02*
Y-31304D01*
X570503Y-48804D01*
Y-31304D01*
G01X582981Y-48804D02*
X581234Y-48512D01*
X579706Y-47346D01*
X578396Y-45596D01*
X577522Y-43554D01*
X577086Y-41221D01*
Y-38887D01*
X577522Y-36554D01*
X578396Y-34512D01*
X579706Y-32763D01*
X581234Y-31596D01*
X582981Y-31304D01*
X584727Y-31596D01*
X586256Y-32763D01*
X587566Y-34512D01*
X588440Y-36554D01*
X588876Y-38887D01*
Y-41221D01*
X588440Y-43554D01*
X587566Y-45596D01*
X586256Y-47346D01*
X584727Y-48512D01*
X582981Y-48804D01*
G01X633822Y-31304D02*
X639281Y-48804D01*
X644740Y-31304D01*
G01X661148Y-48804D02*
X652414D01*
Y-31304D01*
X661148D01*
G01X657654Y-39762D02*
X652414D01*
G01X669914Y-48804D02*
Y-31304D01*
X675373D01*
X677119Y-32179D01*
X678211Y-33346D01*
X678648Y-35679D01*
X678211Y-38013D01*
X676901Y-39471D01*
X675373Y-40346D01*
X669914D01*
G01X675373D02*
X678648Y-48804D01*
G01X691781Y-49387D02*
X691344Y-49096D01*
Y-48512D01*
X691781Y-48221D01*
X692218Y-48512D01*
Y-49096D01*
X691781Y-49387D01*
G01X661383Y-79221D02*
X662693Y-77471D01*
X664221Y-76596D01*
X665968Y-76304D01*
X668151Y-76887D01*
X669679Y-78346D01*
X670116Y-80095D01*
X669898Y-81846D01*
X669024Y-83304D01*
X664658Y-86221D01*
X662693Y-88262D01*
X661383Y-91180D01*
X660946Y-93804D01*
X670116D01*
G01X767364Y-76304D02*
Y-93804D01*
X776098D01*
G01X791851D02*
Y-76304D01*
X783772Y-88846D01*
X794690D01*
G01X801272Y-76304D02*
X806731Y-93804D01*
X812190Y-76304D01*
G01X829034Y-77763D02*
X827724Y-76887D01*
X826196Y-76304D01*
X824449D01*
X822484Y-77179D01*
X820956Y-78637D01*
X819864Y-80388D01*
X818991Y-83304D01*
X818772Y-85929D01*
X819209Y-88554D01*
X819864Y-90304D01*
X821174Y-92054D01*
X822703Y-93221D01*
X824231Y-93804D01*
X825759D01*
X827288Y-93221D01*
X828598Y-92346D01*
X829690Y-91180D01*
G01X846534Y-77763D02*
X845224Y-76887D01*
X843696Y-76304D01*
X841949D01*
X839984Y-77179D01*
X838456Y-78637D01*
X837364Y-80388D01*
X836491Y-83304D01*
X836272Y-85929D01*
X836709Y-88554D01*
X837364Y-90304D01*
X838674Y-92054D01*
X840203Y-93221D01*
X841731Y-93804D01*
X843259D01*
X844788Y-93221D01*
X846098Y-92346D01*
X847190Y-91180D01*
G01X767364Y-31304D02*
Y-48804D01*
X776098D01*
G01X793161D02*
Y-37138D01*
G01Y-39179D02*
X792288Y-38013D01*
X790977Y-37429D01*
X789449Y-37138D01*
X787921Y-37721D01*
X786611Y-38887D01*
X785737Y-40637D01*
X785301Y-42971D01*
X785737Y-45304D01*
X786611Y-47054D01*
X787921Y-48221D01*
X789449Y-48804D01*
X790977Y-48512D01*
X792288Y-47638D01*
X793161Y-46471D01*
G01X802146Y-54054D02*
X803456Y-54637D01*
X805203Y-54054D01*
X806294Y-52888D01*
X807168Y-51429D01*
X808477Y-46763D01*
X811316Y-37138D01*
G01X804329D02*
X808477Y-46763D01*
G01X820956Y-40929D02*
X827943D01*
X827288Y-38887D01*
X826196Y-37721D01*
X824668Y-37138D01*
X823139Y-37429D01*
X821829Y-38304D01*
X820956Y-40346D01*
X820519Y-42096D01*
Y-43846D01*
X820956Y-45596D01*
X822048Y-47346D01*
X823358Y-48512D01*
X824886Y-48804D01*
X826414Y-48221D01*
X827943Y-46471D01*
G01X838674Y-48804D02*
Y-37138D01*
G01Y-39471D02*
X839766Y-38304D01*
X840858Y-37429D01*
X842386Y-37138D01*
X843477Y-37429D01*
X844788Y-38304D01*
G01X931781Y-93804D02*
X930034Y-93512D01*
X928506Y-92346D01*
X927196Y-90596D01*
X926322Y-88554D01*
X925886Y-86221D01*
Y-83887D01*
X926322Y-81554D01*
X927196Y-79512D01*
X928506Y-77763D01*
X930034Y-76596D01*
X931781Y-76304D01*
X933527Y-76596D01*
X935056Y-77763D01*
X936366Y-79512D01*
X937240Y-81554D01*
X937676Y-83887D01*
Y-86221D01*
X937240Y-88554D01*
X936366Y-90596D01*
X935056Y-92346D01*
X933527Y-93512D01*
X931781Y-93804D01*
G01X933527Y-89137D02*
X936148Y-93804D01*
G01X944478Y-76304D02*
Y-88846D01*
X945351Y-91471D01*
X947098Y-93221D01*
X949281Y-93804D01*
X951464Y-93221D01*
X953211Y-91471D01*
X954084Y-88846D01*
Y-76304D01*
G01X964161D02*
X969401D01*
G01X966781D02*
Y-93804D01*
G01X964161D02*
X969401D01*
G01X979259D02*
Y-76304D01*
X989303Y-93804D01*
Y-76304D01*
G01X1006584Y-77763D02*
X1005274Y-76887D01*
X1003746Y-76304D01*
X1001999D01*
X1000034Y-77179D01*
X998506Y-78637D01*
X997414Y-80388D01*
X996541Y-83304D01*
X996322Y-85929D01*
X996759Y-88554D01*
X997414Y-90304D01*
X998724Y-92054D01*
X1000253Y-93221D01*
X1001781Y-93804D01*
X1003309D01*
X1004838Y-93221D01*
X1006148Y-92346D01*
X1007240Y-91180D01*
G01X1019281Y-93804D02*
Y-85929D01*
X1014914Y-76304D01*
G01X1023648D02*
X1019281Y-85929D01*
G01X909478Y-48804D02*
Y-31304D01*
X913844D01*
X915591Y-32179D01*
X916901Y-33346D01*
X917993Y-35095D01*
X918866Y-37138D01*
X919084Y-40054D01*
X918866Y-42971D01*
X917993Y-45013D01*
X916901Y-46763D01*
X915591Y-47929D01*
X913844Y-48804D01*
X909478D01*
G01X928506Y-40929D02*
X935493D01*
X934838Y-38887D01*
X933746Y-37721D01*
X932218Y-37138D01*
X930689Y-37429D01*
X929379Y-38304D01*
X928506Y-40346D01*
X928069Y-42096D01*
Y-43846D01*
X928506Y-45596D01*
X929598Y-47346D01*
X930908Y-48512D01*
X932436Y-48804D01*
X933964Y-48221D01*
X935493Y-46471D01*
G01X946006Y-46763D02*
X947098Y-47929D01*
X948626Y-48804D01*
X949936D01*
X951246Y-48221D01*
X952119Y-47346D01*
X952556Y-46180D01*
X952338Y-44429D01*
X951464Y-43554D01*
X947534Y-41804D01*
X946661Y-39762D01*
X947098Y-38304D01*
X947971Y-37429D01*
X949281Y-37138D01*
X950591Y-37429D01*
X951901Y-38304D01*
G01X966781Y-37138D02*
Y-48804D01*
G01Y-32471D02*
X966344Y-32179D01*
Y-31596D01*
X966781Y-31304D01*
X967218Y-31596D01*
Y-32179D01*
X966781Y-32471D01*
G01X981224Y-53179D02*
X982753Y-54346D01*
X984499Y-54637D01*
X986027Y-54346D01*
X987338Y-52888D01*
X988211Y-50846D01*
Y-37138D01*
G01Y-39471D02*
X987338Y-38304D01*
X986027Y-37429D01*
X984499Y-37138D01*
X982753Y-37721D01*
X981661Y-38887D01*
X980787Y-40929D01*
X980351Y-42971D01*
X980569Y-44721D01*
X981443Y-46763D01*
X982753Y-48221D01*
X984499Y-48804D01*
X985809Y-48512D01*
X987338Y-47346D01*
X988211Y-46180D01*
G01X998069Y-48804D02*
Y-37138D01*
G01Y-40054D02*
X998943Y-38596D01*
X1000253Y-37429D01*
X1001999Y-37138D01*
X1003527Y-37429D01*
X1004838Y-38596D01*
X1005493Y-40637D01*
Y-48804D01*
G01X1016006Y-40929D02*
X1022993D01*
X1022338Y-38887D01*
X1021246Y-37721D01*
X1019718Y-37138D01*
X1018189Y-37429D01*
X1016879Y-38304D01*
X1016006Y-40346D01*
X1015569Y-42096D01*
Y-43846D01*
X1016006Y-45596D01*
X1017098Y-47346D01*
X1018408Y-48512D01*
X1019936Y-48804D01*
X1021464Y-48221D01*
X1022993Y-46471D01*
G01X1033724Y-48804D02*
Y-37138D01*
G01Y-39471D02*
X1034816Y-38304D01*
X1035908Y-37429D01*
X1037436Y-37138D01*
X1038527Y-37429D01*
X1039838Y-38304D01*
G01X1080481Y-76304D02*
X1078734Y-76887D01*
X1077424Y-78346D01*
X1076551Y-80095D01*
X1075896Y-82429D01*
X1075678Y-85054D01*
X1075896Y-87679D01*
X1076551Y-90013D01*
X1077424Y-91763D01*
X1078734Y-93221D01*
X1080481Y-93804D01*
X1082227Y-93221D01*
X1083538Y-91763D01*
X1084411Y-90013D01*
X1085066Y-87679D01*
X1085284Y-85054D01*
X1085066Y-82429D01*
X1084411Y-80095D01*
X1083538Y-78346D01*
X1082227Y-76887D01*
X1080481Y-76304D01*
G01X1097981Y-93804D02*
X1099509Y-93512D01*
X1101256Y-92638D01*
X1102348Y-91180D01*
X1102784Y-89137D01*
X1102348Y-87096D01*
X1101038Y-85346D01*
X1099073Y-84471D01*
X1096889D01*
X1095579Y-83887D01*
X1094487Y-82429D01*
X1094051Y-80388D01*
X1094706Y-78346D01*
X1096234Y-76887D01*
X1097981Y-76304D01*
X1099727Y-76887D01*
X1101256Y-78346D01*
X1101911Y-80388D01*
X1101474Y-82429D01*
X1100383Y-83887D01*
X1099073Y-84471D01*
X1096889D01*
X1094924Y-85346D01*
X1093614Y-87096D01*
X1093178Y-89137D01*
X1093614Y-91180D01*
X1094706Y-92638D01*
X1096453Y-93512D01*
X1097981Y-93804D01*
G01X1111551Y-94387D02*
X1119411Y-76304D01*
G01X1132981D02*
X1131234Y-76887D01*
X1129924Y-78346D01*
X1129051Y-80095D01*
X1128396Y-82429D01*
X1128178Y-85054D01*
X1128396Y-87679D01*
X1129051Y-90013D01*
X1129924Y-91763D01*
X1131234Y-93221D01*
X1132981Y-93804D01*
X1134727Y-93221D01*
X1136038Y-91763D01*
X1136911Y-90013D01*
X1137566Y-87679D01*
X1137784Y-85054D01*
X1137566Y-82429D01*
X1136911Y-80095D01*
X1136038Y-78346D01*
X1134727Y-76887D01*
X1132981Y-76304D01*
G01X1150044Y-93804D02*
X1150481Y-90013D01*
X1151136Y-86804D01*
X1152009Y-83887D01*
X1153101Y-80679D01*
X1154848Y-76304D01*
X1146114D01*
G01X1164051Y-94387D02*
X1171911Y-76304D01*
G01X1181333Y-79221D02*
X1182643Y-77471D01*
X1184171Y-76596D01*
X1185918Y-76304D01*
X1188101Y-76887D01*
X1189629Y-78346D01*
X1190066Y-80095D01*
X1189848Y-81846D01*
X1188974Y-83304D01*
X1184608Y-86221D01*
X1182643Y-88262D01*
X1181333Y-91180D01*
X1180896Y-93804D01*
X1190066D01*
G01X1202981Y-76304D02*
X1201234Y-76887D01*
X1199924Y-78346D01*
X1199051Y-80095D01*
X1198396Y-82429D01*
X1198178Y-85054D01*
X1198396Y-87679D01*
X1199051Y-90013D01*
X1199924Y-91763D01*
X1201234Y-93221D01*
X1202981Y-93804D01*
X1204727Y-93221D01*
X1206038Y-91763D01*
X1206911Y-90013D01*
X1207566Y-87679D01*
X1207784Y-85054D01*
X1207566Y-82429D01*
X1206911Y-80095D01*
X1206038Y-78346D01*
X1204727Y-76887D01*
X1202981Y-76304D01*
G01X1220481Y-93804D02*
Y-76304D01*
X1217861Y-79804D01*
G01Y-93804D02*
X1223101D01*
G01X1237544D02*
X1237981Y-90013D01*
X1238636Y-86804D01*
X1239509Y-83887D01*
X1240601Y-80679D01*
X1242348Y-76304D01*
X1233614D01*
G01X1128178Y-48804D02*
Y-31304D01*
X1132544D01*
X1134291Y-32179D01*
X1135601Y-33346D01*
X1136693Y-35095D01*
X1137566Y-37138D01*
X1137784Y-40054D01*
X1137566Y-42971D01*
X1136693Y-45013D01*
X1135601Y-46763D01*
X1134291Y-47929D01*
X1132544Y-48804D01*
X1128178D01*
G01X1154411D02*
Y-37138D01*
G01Y-39179D02*
X1153538Y-38013D01*
X1152227Y-37429D01*
X1150699Y-37138D01*
X1149171Y-37721D01*
X1147861Y-38887D01*
X1146987Y-40637D01*
X1146551Y-42971D01*
X1146987Y-45304D01*
X1147861Y-47054D01*
X1149171Y-48221D01*
X1150699Y-48804D01*
X1152227Y-48512D01*
X1153538Y-47638D01*
X1154411Y-46471D01*
G01X1167981Y-31304D02*
Y-48804D01*
G01X1164924Y-37138D02*
X1171038D01*
G01X1182206Y-40929D02*
X1189193D01*
X1188538Y-38887D01*
X1187446Y-37721D01*
X1185918Y-37138D01*
X1184389Y-37429D01*
X1183079Y-38304D01*
X1182206Y-40346D01*
X1181769Y-42096D01*
Y-43846D01*
X1182206Y-45596D01*
X1183298Y-47346D01*
X1184608Y-48512D01*
X1186136Y-48804D01*
X1187664Y-48221D01*
X1189193Y-46471D01*
M02*
